G04 ================== begin FILE IDENTIFICATION RECORD ==================*
G04 Layout Name:  D:/<user>/Wistron_project/16317-1/gbr/16317-1.brd*
G04 Film Name:    BMASK*
G04 File Format:  Gerber RS274X*
G04 File Origin:  Cadence Allegro 16.5-S056*
G04 Origin Date:  Fri Jun 09 15:52:34 2017*
G04 *
G04 Layer:  VIA CLASS/SOLDERMASK_BOTTOM*
G04 Layer:  PIN/SOLDERMASK_BOTTOM*
G04 Layer:  PACKAGE GEOMETRY/SOLDERMASK_BOTTOM*
G04 Layer:  DRAWING FORMAT/LAYER_PCB_STORY*
G04 Layer:  DRAWING FORMAT/LAYER_SOLDER_B*
G04 Layer:  BOARD GEOMETRY/SOLDERMASK_BOTTOM*
G04 *
G04 Offset:    (0.00 0.00)*
G04 Mirror:    No*
G04 Mode:      Positive*
G04 Rotation:  0*
G04 FullContactRelief:  No*
G04 UndefLineWidth:     6.00*
G04 ================== end FILE IDENTIFICATION RECORD ====================*
%FSLAX35Y35*MOIN*%
%IR0*IPPOS*OFA0.00000B0.00000*MIA0B0*SFA1.00000B1.00000*%
%AMMACRO56*
4,1,40,.011,.007,
.011,-.007,
.010939,-.007695,
.010759,-.008368,
.010464,-.009,
.010064,-.009571,
.009571,-.010064,
.009,-.010464,
.008368,-.010759,
.007695,-.010939,
.007,-.011,
-.007,-.011,
-.007695,-.010939,
-.008368,-.010759,
-.009,-.010464,
-.009571,-.010064,
-.010064,-.009571,
-.010464,-.009,
-.010759,-.008368,
-.010939,-.007695,
-.011,-.007,
-.011,.007,
-.010939,.007695,
-.010759,.008368,
-.010464,.009,
-.010064,.009571,
-.009571,.010064,
-.009,.010464,
-.008368,.010759,
-.007695,.010939,
-.007,.011,
.007,.011,
.007695,.010939,
.008368,.010759,
.009,.010464,
.009571,.010064,
.010064,.009571,
.010464,.009,
.010759,.008368,
.010939,.007695,
.011,.007,
0.0*
%
%ADD56MACRO56*%
%AMMACRO44*
4,1,40,.013,-.017,
-.013,-.017,
-.013695,-.016939,
-.014368,-.016759,
-.015,-.016464,
-.015571,-.016064,
-.016064,-.015571,
-.016464,-.015,
-.016759,-.014368,
-.016939,-.013695,
-.017,-.013,
-.017,.013,
-.016939,.013695,
-.016759,.014368,
-.016464,.015,
-.016064,.015571,
-.015571,.016064,
-.015,.016464,
-.014368,.016759,
-.013695,.016939,
-.013,.017,
.013,.017,
.013695,.016939,
.014368,.016759,
.015,.016464,
.015571,.016064,
.016064,.015571,
.016464,.015,
.016759,.014368,
.016939,.013695,
.017,.013,
.017,-.013,
.016939,-.013695,
.016759,-.014368,
.016464,-.015,
.016064,-.015571,
.015571,-.016064,
.015,-.016464,
.014368,-.016759,
.013695,-.016939,
.013,-.017,
0.0*
%
%ADD44MACRO44*%
%AMMACRO24*
4,1,40,-.017,-.013,
-.017,.013,
-.016939,.013695,
-.016759,.014368,
-.016464,.015,
-.016064,.015571,
-.015571,.016064,
-.015,.016464,
-.014368,.016759,
-.013695,.016939,
-.013,.017,
.013,.017,
.013695,.016939,
.014368,.016759,
.015,.016464,
.015571,.016064,
.016064,.015571,
.016464,.015,
.016759,.014368,
.016939,.013695,
.017,.013,
.017,-.013,
.016939,-.013695,
.016759,-.014368,
.016464,-.015,
.016064,-.015571,
.015571,-.016064,
.015,-.016464,
.014368,-.016759,
.013695,-.016939,
.013,-.017,
-.013,-.017,
-.013695,-.016939,
-.014368,-.016759,
-.015,-.016464,
-.015571,-.016064,
-.016064,-.015571,
-.016464,-.015,
-.016759,-.014368,
-.016939,-.013695,
-.017,-.013,
0.0*
%
%ADD24MACRO24*%
%ADD48R,.01X.007*%
%ADD12C,.02*%
%ADD59C,.03*%
%ADD32C,.022*%
%ADD66C,.032*%
%ADD34C,.05*%
%ADD31C,.024*%
%ADD33C,.016*%
%ADD37C,.053*%
%ADD10C,.08*%
%ADD35C,.037*%
%ADD51C,.056*%
%ADD63C,.048*%
%ADD11C,.086*%
%ADD70R,.062X.062*%
%AMMACRO54*
4,1,40,.007,-.0225,
.008389,-.022378,
.009736,-.022018,
.011,-.021428,
.012142,-.020628,
.013128,-.019642,
.013928,-.0185,
.014518,-.017236,
.014878,-.015889,
.015,-.0145,
.015,.0145,
.014878,.015889,
.014518,.017236,
.013928,.0185,
.013128,.019642,
.012142,.020628,
.011,.021428,
.009736,.022018,
.008389,.022378,
.007,.0225,
-.007,.0225,
-.008389,.022378,
-.009736,.022018,
-.011,.021428,
-.012142,.020628,
-.013128,.019642,
-.013928,.0185,
-.014518,.017236,
-.014878,.015889,
-.015,.0145,
-.015,-.0145,
-.014878,-.015889,
-.014518,-.017236,
-.013928,-.0185,
-.013128,-.019642,
-.012142,-.020628,
-.011,-.021428,
-.009736,-.022018,
-.008389,-.022378,
-.007,-.0225,
.007,-.0225,
0.0*
%
%ADD54MACRO54*%
%ADD50C,.099*%
%AMMACRO64*
4,1,40,.007,-.011,
-.007,-.011,
-.007695,-.010939,
-.008368,-.010759,
-.009,-.010464,
-.009571,-.010064,
-.010064,-.009571,
-.010464,-.009,
-.010759,-.008368,
-.010939,-.007695,
-.011,-.007,
-.011,.007,
-.010939,.007695,
-.010759,.008368,
-.010464,.009,
-.010064,.009571,
-.009571,.010064,
-.009,.010464,
-.008368,.010759,
-.007695,.010939,
-.007,.011,
.007,.011,
.007695,.010939,
.008368,.010759,
.009,.010464,
.009571,.010064,
.010064,.009571,
.010464,.009,
.010759,.008368,
.010939,.007695,
.011,.007,
.011,-.007,
.010939,-.007695,
.010759,-.008368,
.010464,-.009,
.010064,-.009571,
.009571,-.010064,
.009,-.010464,
.008368,-.010759,
.007695,-.010939,
.007,-.011,
0.0*
%
%ADD64MACRO64*%
%AMMACRO17*
4,1,40,-.011,-.007,
-.011,.007,
-.010939,.007695,
-.010759,.008368,
-.010464,.009,
-.010064,.009571,
-.009571,.010064,
-.009,.010464,
-.008368,.010759,
-.007695,.010939,
-.007,.011,
.007,.011,
.007695,.010939,
.008368,.010759,
.009,.010464,
.009571,.010064,
.010064,.009571,
.010464,.009,
.010759,.008368,
.010939,.007695,
.011,.007,
.011,-.007,
.010939,-.007695,
.010759,-.008368,
.010464,-.009,
.010064,-.009571,
.009571,-.010064,
.009,-.010464,
.008368,-.010759,
.007695,-.010939,
.007,-.011,
-.007,-.011,
-.007695,-.010939,
-.008368,-.010759,
-.009,-.010464,
-.009571,-.010064,
-.010064,-.009571,
-.010464,-.009,
-.010759,-.008368,
-.010939,-.007695,
-.011,-.007,
0.0*
%
%ADD17MACRO17*%
%AMMACRO16*
4,1,40,-.012,-.008,
-.012,.008,
-.011939,.008695,
-.011759,.009368,
-.011464,.01,
-.011064,.010571,
-.010571,.011064,
-.01,.011464,
-.009368,.011759,
-.008695,.011939,
-.008,.012,
.008,.012,
.008695,.011939,
.009368,.011759,
.01,.011464,
.010571,.011064,
.011064,.010571,
.011464,.01,
.011759,.009368,
.011939,.008695,
.012,.008,
.012,-.008,
.011939,-.008695,
.011759,-.009368,
.011464,-.01,
.011064,-.010571,
.010571,-.011064,
.01,-.011464,
.009368,-.011759,
.008695,-.011939,
.008,-.012,
-.008,-.012,
-.008695,-.011939,
-.009368,-.011759,
-.01,-.011464,
-.010571,-.011064,
-.011064,-.010571,
-.011464,-.01,
-.011759,-.009368,
-.011939,-.008695,
-.012,-.008,
0.0*
%
%ADD16MACRO16*%
%AMMACRO58*
4,1,40,-.008,.012,
.008,.012,
.008695,.011939,
.009368,.011759,
.01,.011464,
.010571,.011064,
.011064,.010571,
.011464,.01,
.011759,.009368,
.011939,.008695,
.012,.008,
.012,-.008,
.011939,-.008695,
.011759,-.009368,
.011464,-.01,
.011064,-.010571,
.010571,-.011064,
.01,-.011464,
.009368,-.011759,
.008695,-.011939,
.008,-.012,
-.008,-.012,
-.008695,-.011939,
-.009368,-.011759,
-.01,-.011464,
-.010571,-.011064,
-.011064,-.010571,
-.011464,-.01,
-.011759,-.009368,
-.011939,-.008695,
-.012,-.008,
-.012,.008,
-.011939,.008695,
-.011759,.009368,
-.011464,.01,
-.011064,.010571,
-.010571,.011064,
-.01,.011464,
-.009368,.011759,
-.008695,.011939,
-.008,.012,
0.0*
%
%ADD58MACRO58*%
%AMMACRO21*
4,1,40,-.013,.017,
.013,.017,
.013695,.016939,
.014368,.016759,
.015,.016464,
.015571,.016064,
.016064,.015571,
.016464,.015,
.016759,.014368,
.016939,.013695,
.017,.013,
.017,-.013,
.016939,-.013695,
.016759,-.014368,
.016464,-.015,
.016064,-.015571,
.015571,-.016064,
.015,-.016464,
.014368,-.016759,
.013695,-.016939,
.013,-.017,
-.013,-.017,
-.013695,-.016939,
-.014368,-.016759,
-.015,-.016464,
-.015571,-.016064,
-.016064,-.015571,
-.016464,-.015,
-.016759,-.014368,
-.016939,-.013695,
-.017,-.013,
-.017,.013,
-.016939,.013695,
-.016759,.014368,
-.016464,.015,
-.016064,.015571,
-.015571,.016064,
-.015,.016464,
-.014368,.016759,
-.013695,.016939,
-.013,.017,
0.0*
%
%ADD21MACRO21*%
%AMMACRO67*
4,1,40,.017,.013,
.017,-.013,
.016939,-.013695,
.016759,-.014368,
.016464,-.015,
.016064,-.015571,
.015571,-.016064,
.015,-.016464,
.014368,-.016759,
.013695,-.016939,
.013,-.017,
-.013,-.017,
-.013695,-.016939,
-.014368,-.016759,
-.015,-.016464,
-.015571,-.016064,
-.016064,-.015571,
-.016464,-.015,
-.016759,-.014368,
-.016939,-.013695,
-.017,-.013,
-.017,.013,
-.016939,.013695,
-.016759,.014368,
-.016464,.015,
-.016064,.015571,
-.015571,.016064,
-.015,.016464,
-.014368,.016759,
-.013695,.016939,
-.013,.017,
.013,.017,
.013695,.016939,
.014368,.016759,
.015,.016464,
.015571,.016064,
.016064,.015571,
.016464,.015,
.016759,.014368,
.016939,.013695,
.017,.013,
0.0*
%
%ADD67MACRO67*%
%AMMACRO28*
4,1,6,.025,-.0135,
.005,.0065,
.005,.0135,
-.005,.0135,
-.005,.0065,
-.025,-.0135,
.025,-.0135,
0.0*
%
%ADD28MACRO28*%
%AMMACRO65*
4,1,40,.007,-.011,
-.007,-.011,
-.007695,-.010939,
-.008368,-.010759,
-.009,-.010464,
-.009571,-.010064,
-.010064,-.009571,
-.010464,-.009,
-.010759,-.008368,
-.010939,-.007695,
-.011,-.007,
-.011,.007,
-.010939,.007695,
-.010759,.008368,
-.010464,.009,
-.010064,.009571,
-.009571,.010064,
-.009,.010464,
-.008368,.010759,
-.007695,.010939,
-.007,.011,
.007,.011,
.007695,.010939,
.008368,.010759,
.009,.010464,
.009571,.010064,
.010064,.009571,
.010464,.009,
.010759,.008368,
.010939,.007695,
.011,.007,
.011,-.007,
.010939,-.007695,
.010759,-.008368,
.010464,-.009,
.010064,-.009571,
.009571,-.010064,
.009,-.010464,
.008368,-.010759,
.007695,-.010939,
.007,-.011,
0.0*
%
%ADD65MACRO65*%
%AMMACRO18*
4,1,40,-.011,-.007,
-.011,.007,
-.010939,.007695,
-.010759,.008368,
-.010464,.009,
-.010064,.009571,
-.009571,.010064,
-.009,.010464,
-.008368,.010759,
-.007695,.010939,
-.007,.011,
.007,.011,
.007695,.010939,
.008368,.010759,
.009,.010464,
.009571,.010064,
.010064,.009571,
.010464,.009,
.010759,.008368,
.010939,.007695,
.011,.007,
.011,-.007,
.010939,-.007695,
.010759,-.008368,
.010464,-.009,
.010064,-.009571,
.009571,-.010064,
.009,-.010464,
.008368,-.010759,
.007695,-.010939,
.007,-.011,
-.007,-.011,
-.007695,-.010939,
-.008368,-.010759,
-.009,-.010464,
-.009571,-.010064,
-.010064,-.009571,
-.010464,-.009,
-.010759,-.008368,
-.010939,-.007695,
-.011,-.007,
0.0*
%
%ADD18MACRO18*%
%AMMACRO15*
4,1,40,-.012,-.008,
-.012,.008,
-.011939,.008695,
-.011759,.009368,
-.011464,.01,
-.011064,.010571,
-.010571,.011064,
-.01,.011464,
-.009368,.011759,
-.008695,.011939,
-.008,.012,
.008,.012,
.008695,.011939,
.009368,.011759,
.01,.011464,
.010571,.011064,
.011064,.010571,
.011464,.01,
.011759,.009368,
.011939,.008695,
.012,.008,
.012,-.008,
.011939,-.008695,
.011759,-.009368,
.011464,-.01,
.011064,-.010571,
.010571,-.011064,
.01,-.011464,
.009368,-.011759,
.008695,-.011939,
.008,-.012,
-.008,-.012,
-.008695,-.011939,
-.009368,-.011759,
-.01,-.011464,
-.010571,-.011064,
-.011064,-.010571,
-.011464,-.01,
-.011759,-.009368,
-.011939,-.008695,
-.012,-.008,
0.0*
%
%ADD15MACRO15*%
%AMMACRO57*
4,1,40,-.008,.012,
.008,.012,
.008695,.011939,
.009368,.011759,
.01,.011464,
.010571,.011064,
.011064,.010571,
.011464,.01,
.011759,.009368,
.011939,.008695,
.012,.008,
.012,-.008,
.011939,-.008695,
.011759,-.009368,
.011464,-.01,
.011064,-.010571,
.010571,-.011064,
.01,-.011464,
.009368,-.011759,
.008695,-.011939,
.008,-.012,
-.008,-.012,
-.008695,-.011939,
-.009368,-.011759,
-.01,-.011464,
-.010571,-.011064,
-.011064,-.010571,
-.011464,-.01,
-.011759,-.009368,
-.011939,-.008695,
-.012,-.008,
-.012,.008,
-.011939,.008695,
-.011759,.009368,
-.011464,.01,
-.011064,.010571,
-.010571,.011064,
-.01,.011464,
-.009368,.011759,
-.008695,.011939,
-.008,.012,
0.0*
%
%ADD57MACRO57*%
%AMMACRO22*
4,1,40,-.013,.017,
.013,.017,
.013695,.016939,
.014368,.016759,
.015,.016464,
.015571,.016064,
.016064,.015571,
.016464,.015,
.016759,.014368,
.016939,.013695,
.017,.013,
.017,-.013,
.016939,-.013695,
.016759,-.014368,
.016464,-.015,
.016064,-.015571,
.015571,-.016064,
.015,-.016464,
.014368,-.016759,
.013695,-.016939,
.013,-.017,
-.013,-.017,
-.013695,-.016939,
-.014368,-.016759,
-.015,-.016464,
-.015571,-.016064,
-.016064,-.015571,
-.016464,-.015,
-.016759,-.014368,
-.016939,-.013695,
-.017,-.013,
-.017,.013,
-.016939,.013695,
-.016759,.014368,
-.016464,.015,
-.016064,.015571,
-.015571,.016064,
-.015,.016464,
-.014368,.016759,
-.013695,.016939,
-.013,.017,
0.0*
%
%ADD22MACRO22*%
%AMMACRO68*
4,1,40,.017,.013,
.017,-.013,
.016939,-.013695,
.016759,-.014368,
.016464,-.015,
.016064,-.015571,
.015571,-.016064,
.015,-.016464,
.014368,-.016759,
.013695,-.016939,
.013,-.017,
-.013,-.017,
-.013695,-.016939,
-.014368,-.016759,
-.015,-.016464,
-.015571,-.016064,
-.016064,-.015571,
-.016464,-.015,
-.016759,-.014368,
-.016939,-.013695,
-.017,-.013,
-.017,.013,
-.016939,.013695,
-.016759,.014368,
-.016464,.015,
-.016064,.015571,
-.015571,.016064,
-.015,.016464,
-.014368,.016759,
-.013695,.016939,
-.013,.017,
.013,.017,
.013695,.016939,
.014368,.016759,
.015,.016464,
.015571,.016064,
.016064,.015571,
.016464,.015,
.016759,.014368,
.016939,.013695,
.017,.013,
0.0*
%
%ADD68MACRO68*%
%ADD61R,.06X.03*%
%ADD53R,.022X.04*%
%ADD45R,.13X.128*%
%ADD46C,.101*%
%ADD30R,.044X.012*%
%ADD73R,.036X.012*%
%ADD71R,.012X.036*%
%ADD62R,.105X.128*%
%ADD38C,.111*%
%ADD74R,.037X.012*%
%ADD72R,.012X.037*%
%ADD69R,.05X.065*%
%ADD52C,.404*%
%ADD49C,.126*%
%ADD26R,.045X.055*%
%ADD47C,.119*%
%ADD25R,.055X.045*%
%ADD75C,.138*%
%ADD60R,.073X.047*%
%ADD40R,.095X.09*%
%ADD36C,.375*%
%ADD39O,.552X.788*%
%AMMACRO42*
4,1,40,.012,.008,
.012,-.008,
.011939,-.008695,
.011759,-.009368,
.011464,-.01,
.011064,-.010571,
.010571,-.011064,
.01,-.011464,
.009368,-.011759,
.008695,-.011939,
.008,-.012,
-.008,-.012,
-.008695,-.011939,
-.009368,-.011759,
-.01,-.011464,
-.010571,-.011064,
-.011064,-.010571,
-.011464,-.01,
-.011759,-.009368,
-.011939,-.008695,
-.012,-.008,
-.012,.008,
-.011939,.008695,
-.011759,.009368,
-.011464,.01,
-.011064,.010571,
-.010571,.011064,
-.01,.011464,
-.009368,.011759,
-.008695,.011939,
-.008,.012,
.008,.012,
.008695,.011939,
.009368,.011759,
.01,.011464,
.010571,.011064,
.011064,.010571,
.011464,.01,
.011759,.009368,
.011939,.008695,
.012,.008,
0.0*
%
%ADD42MACRO42*%
%AMMACRO19*
4,1,40,-.007,.011,
.007,.011,
.007695,.010939,
.008368,.010759,
.009,.010464,
.009571,.010064,
.010064,.009571,
.010464,.009,
.010759,.008368,
.010939,.007695,
.011,.007,
.011,-.007,
.010939,-.007695,
.010759,-.008368,
.010464,-.009,
.010064,-.009571,
.009571,-.010064,
.009,-.010464,
.008368,-.010759,
.007695,-.010939,
.007,-.011,
-.007,-.011,
-.007695,-.010939,
-.008368,-.010759,
-.009,-.010464,
-.009571,-.010064,
-.010064,-.009571,
-.010464,-.009,
-.010759,-.008368,
-.010939,-.007695,
-.011,-.007,
-.011,.007,
-.010939,.007695,
-.010759,.008368,
-.010464,.009,
-.010064,.009571,
-.009571,.010064,
-.009,.010464,
-.008368,.010759,
-.007695,.010939,
-.007,.011,
0.0*
%
%ADD19MACRO19*%
%AMMACRO14*
4,1,40,.008,-.012,
-.008,-.012,
-.008695,-.011939,
-.009368,-.011759,
-.01,-.011464,
-.010571,-.011064,
-.011064,-.010571,
-.011464,-.01,
-.011759,-.009368,
-.011939,-.008695,
-.012,-.008,
-.012,.008,
-.011939,.008695,
-.011759,.009368,
-.011464,.01,
-.011064,.010571,
-.010571,.011064,
-.01,.011464,
-.009368,.011759,
-.008695,.011939,
-.008,.012,
.008,.012,
.008695,.011939,
.009368,.011759,
.01,.011464,
.010571,.011064,
.011064,.010571,
.011464,.01,
.011759,.009368,
.011939,.008695,
.012,.008,
.012,-.008,
.011939,-.008695,
.011759,-.009368,
.011464,-.01,
.011064,-.010571,
.010571,-.011064,
.01,-.011464,
.009368,-.011759,
.008695,-.011939,
.008,-.012,
0.0*
%
%ADD14MACRO14*%
%AMMACRO55*
4,1,40,.011,.007,
.011,-.007,
.010939,-.007695,
.010759,-.008368,
.010464,-.009,
.010064,-.009571,
.009571,-.010064,
.009,-.010464,
.008368,-.010759,
.007695,-.010939,
.007,-.011,
-.007,-.011,
-.007695,-.010939,
-.008368,-.010759,
-.009,-.010464,
-.009571,-.010064,
-.010064,-.009571,
-.010464,-.009,
-.010759,-.008368,
-.010939,-.007695,
-.011,-.007,
-.011,.007,
-.010939,.007695,
-.010759,.008368,
-.010464,.009,
-.010064,.009571,
-.009571,.010064,
-.009,.010464,
-.008368,.010759,
-.007695,.010939,
-.007,.011,
.007,.011,
.007695,.010939,
.008368,.010759,
.009,.010464,
.009571,.010064,
.010064,.009571,
.010464,.009,
.010759,.008368,
.010939,.007695,
.011,.007,
0.0*
%
%ADD55MACRO55*%
%AMMACRO43*
4,1,40,.013,-.017,
-.013,-.017,
-.013695,-.016939,
-.014368,-.016759,
-.015,-.016464,
-.015571,-.016064,
-.016064,-.015571,
-.016464,-.015,
-.016759,-.014368,
-.016939,-.013695,
-.017,-.013,
-.017,.013,
-.016939,.013695,
-.016759,.014368,
-.016464,.015,
-.016064,.015571,
-.015571,.016064,
-.015,.016464,
-.014368,.016759,
-.013695,.016939,
-.013,.017,
.013,.017,
.013695,.016939,
.014368,.016759,
.015,.016464,
.015571,.016064,
.016064,.015571,
.016464,.015,
.016759,.014368,
.016939,.013695,
.017,.013,
.017,-.013,
.016939,-.013695,
.016759,-.014368,
.016464,-.015,
.016064,-.015571,
.015571,-.016064,
.015,-.016464,
.014368,-.016759,
.013695,-.016939,
.013,-.017,
0.0*
%
%ADD43MACRO43*%
%AMMACRO23*
4,1,40,-.017,-.013,
-.017,.013,
-.016939,.013695,
-.016759,.014368,
-.016464,.015,
-.016064,.015571,
-.015571,.016064,
-.015,.016464,
-.014368,.016759,
-.013695,.016939,
-.013,.017,
.013,.017,
.013695,.016939,
.014368,.016759,
.015,.016464,
.015571,.016064,
.016064,.015571,
.016464,.015,
.016759,.014368,
.016939,.013695,
.017,.013,
.017,-.013,
.016939,-.013695,
.016759,-.014368,
.016464,-.015,
.016064,-.015571,
.015571,-.016064,
.015,-.016464,
.014368,-.016759,
.013695,-.016939,
.013,-.017,
-.013,-.017,
-.013695,-.016939,
-.014368,-.016759,
-.015,-.016464,
-.015571,-.016064,
-.016064,-.015571,
-.016464,-.015,
-.016759,-.014368,
-.016939,-.013695,
-.017,-.013,
0.0*
%
%ADD23MACRO23*%
%AMMACRO27*
4,1,6,.005,-.0135,
.005,-.0065,
.025,.0135,
-.025,.0135,
-.005,-.0065,
-.005,-.0135,
.005,-.0135,
0.0*
%
%ADD27MACRO27*%
%AMMACRO29*
4,1,20,-.0635,-.1075,
-.049,-.1075,
-.049,-.118,
-.0395,-.118,
-.0395,-.1075,
.0395,-.1075,
.0395,-.118,
.049,-.118,
.049,-.1075,
.0635,-.1075,
.0635,.1075,
.049,.1075,
.049,.118,
.0395,.118,
.0395,.1075,
-.0395,.1075,
-.0395,.118,
-.049,.118,
-.049,.1075,
-.0635,.1075,
-.0635,-.1075,
0.0*
%
%ADD29MACRO29*%
%AMMACRO41*
4,1,40,.012,.008,
.012,-.008,
.011939,-.008695,
.011759,-.009368,
.011464,-.01,
.011064,-.010571,
.010571,-.011064,
.01,-.011464,
.009368,-.011759,
.008695,-.011939,
.008,-.012,
-.008,-.012,
-.008695,-.011939,
-.009368,-.011759,
-.01,-.011464,
-.010571,-.011064,
-.011064,-.010571,
-.011464,-.01,
-.011759,-.009368,
-.011939,-.008695,
-.012,-.008,
-.012,.008,
-.011939,.008695,
-.011759,.009368,
-.011464,.01,
-.011064,.010571,
-.010571,.011064,
-.01,.011464,
-.009368,.011759,
-.008695,.011939,
-.008,.012,
.008,.012,
.008695,.011939,
.009368,.011759,
.01,.011464,
.010571,.011064,
.011064,.010571,
.011464,.01,
.011759,.009368,
.011939,.008695,
.012,.008,
0.0*
%
%ADD41MACRO41*%
%AMMACRO20*
4,1,40,-.007,.011,
.007,.011,
.007695,.010939,
.008368,.010759,
.009,.010464,
.009571,.010064,
.010064,.009571,
.010464,.009,
.010759,.008368,
.010939,.007695,
.011,.007,
.011,-.007,
.010939,-.007695,
.010759,-.008368,
.010464,-.009,
.010064,-.009571,
.009571,-.010064,
.009,-.010464,
.008368,-.010759,
.007695,-.010939,
.007,-.011,
-.007,-.011,
-.007695,-.010939,
-.008368,-.010759,
-.009,-.010464,
-.009571,-.010064,
-.010064,-.009571,
-.010464,-.009,
-.010759,-.008368,
-.010939,-.007695,
-.011,-.007,
-.011,.007,
-.010939,.007695,
-.010759,.008368,
-.010464,.009,
-.010064,.009571,
-.009571,.010064,
-.009,.010464,
-.008368,.010759,
-.007695,.010939,
-.007,.011,
0.0*
%
%ADD20MACRO20*%
%AMMACRO13*
4,1,40,.008,-.012,
-.008,-.012,
-.008695,-.011939,
-.009368,-.011759,
-.01,-.011464,
-.010571,-.011064,
-.011064,-.010571,
-.011464,-.01,
-.011759,-.009368,
-.011939,-.008695,
-.012,-.008,
-.012,.008,
-.011939,.008695,
-.011759,.009368,
-.011464,.01,
-.011064,.010571,
-.010571,.011064,
-.01,.011464,
-.009368,.011759,
-.008695,.011939,
-.008,.012,
.008,.012,
.008695,.011939,
.009368,.011759,
.01,.011464,
.010571,.011064,
.011064,.010571,
.011464,.01,
.011759,.009368,
.011939,.008695,
.012,.008,
.012,-.008,
.011939,-.008695,
.011759,-.009368,
.011464,-.01,
.011064,-.010571,
.010571,-.011064,
.01,-.011464,
.009368,-.011759,
.008695,-.011939,
.008,-.012,
0.0*
%
%ADD13MACRO13*%
%ADD76C,.006*%
G75*
%LPD*%
G75*
G36*
G01X804631Y1302185D02*
X796031D01*
Y1311185D01*
X804631D01*
Y1302185D01*
G37*
G36*
G01Y1322985D02*
X796031D01*
Y1313985D01*
X804631D01*
Y1322985D01*
G37*
G36*
G01X793231Y1313985D02*
X784631D01*
Y1322985D01*
X793231D01*
Y1313985D01*
G37*
G36*
G01X784631Y1302185D02*
X793231D01*
Y1311185D01*
X784631D01*
Y1302185D01*
G37*
G36*
G01X805101Y1344691D02*
X796501D01*
Y1353691D01*
X805101D01*
Y1344691D01*
G37*
G36*
G01Y1365491D02*
X796501D01*
Y1356491D01*
X805101D01*
Y1365491D01*
G37*
G36*
G01X793701Y1356491D02*
X785101D01*
Y1365491D01*
X793701D01*
Y1356491D01*
G37*
G36*
G01X785101Y1344691D02*
X793701D01*
Y1353691D01*
X785101D01*
Y1344691D01*
G37*
G36*
G01X804880Y1382359D02*
X796280D01*
Y1391359D01*
X804880D01*
Y1382359D01*
G37*
G36*
G01Y1403159D02*
X796280D01*
Y1394159D01*
X804880D01*
Y1403159D01*
G37*
G36*
G01X793480Y1394159D02*
X784880D01*
Y1403159D01*
X793480D01*
Y1394159D01*
G37*
G36*
G01X784880Y1382359D02*
X793480D01*
Y1391359D01*
X784880D01*
Y1382359D01*
G37*
G54D10*
X34900Y34200D03*
X40600Y1464400D03*
X1894200Y1471300D03*
G54D20*
X94600Y904300D03*
X192427Y466564D03*
X658600Y1464000D03*
Y1468000D03*
Y1453500D03*
Y1457500D03*
X1005289Y1092328D03*
X1024287Y1109799D03*
X1735196Y469982D03*
X1809500Y904300D03*
G54D11*
X59400Y32600D03*
X63374Y1454500D03*
X390757Y1511515D03*
X812347Y17406D03*
X885639Y1511515D03*
X1187163Y158305D03*
X1538001Y1511515D03*
X1869500Y1461500D03*
G54D30*
X75357Y895343D03*
Y893374D03*
Y891406D03*
Y889437D03*
Y887469D03*
Y885500D03*
Y883531D03*
Y881563D03*
Y879594D03*
Y877626D03*
Y875657D03*
X94643D03*
Y877626D03*
Y879594D03*
Y881563D03*
Y883531D03*
Y885500D03*
Y887469D03*
Y889437D03*
Y891406D03*
Y893374D03*
Y895343D03*
X173184Y457607D03*
Y455638D03*
Y453670D03*
Y451701D03*
Y449733D03*
Y447764D03*
Y445795D03*
Y443827D03*
Y441858D03*
Y439890D03*
Y437921D03*
X192470D03*
Y439890D03*
Y441858D03*
Y443827D03*
Y445795D03*
Y447764D03*
Y449733D03*
Y451701D03*
Y453670D03*
Y455638D03*
Y457607D03*
X1715953Y461025D03*
Y459056D03*
Y457088D03*
Y455119D03*
Y453151D03*
Y451182D03*
Y449213D03*
Y447245D03*
Y445276D03*
Y443308D03*
Y441339D03*
X1735239D03*
Y443308D03*
Y445276D03*
Y447245D03*
Y449213D03*
Y451182D03*
Y453151D03*
Y455119D03*
Y457088D03*
Y459056D03*
Y461025D03*
X1790357Y895343D03*
Y893374D03*
Y891406D03*
Y889437D03*
Y887469D03*
Y885500D03*
Y883531D03*
Y881563D03*
Y879594D03*
Y877626D03*
Y875657D03*
X1809643D03*
Y877626D03*
Y879594D03*
Y881563D03*
Y883531D03*
Y885500D03*
Y887469D03*
Y889437D03*
Y891406D03*
Y893374D03*
Y895343D03*
G54D21*
X65563Y887525D03*
X163390Y449789D03*
X1027363Y1114199D03*
X1002300Y1099000D03*
X984300Y1126800D03*
X1706159Y453207D03*
X1780563Y887525D03*
G54D12*
G01X466941Y-145664D02*
Y-225664D01*
G01D02*
X1593241D01*
G01X462941Y-129664D02*
G02I-12000J0D01*
G01X457791D02*
G02I-6850J0D01*
G01X450941Y-145664D02*
Y-113664D01*
G01X466941Y-129664D02*
X434941D01*
G01X466941Y-145664D02*
X1593241D01*
G01X466941Y-181164D02*
X1593241D01*
G01X805741Y-145664D02*
Y-225664D01*
G01X943241Y-145664D02*
Y-225664D01*
G01X1058241Y-145664D02*
Y-225664D01*
G01X1225741Y-145664D02*
Y-225664D01*
G01X1395741Y-145664D02*
Y-225664D01*
G01X1593241Y-145664D02*
Y-225664D01*
G01X1621241Y-129664D02*
G02I-12000J0D01*
G01X1616091D02*
G02I-6850J0D01*
G01X1609241Y-145664D02*
Y-113664D01*
G01X1625241Y-129664D02*
X1593241D01*
X100412Y6000D03*
X95412D03*
X90412D03*
X85412D03*
X80412D03*
X75412D03*
X70412D03*
X65412D03*
X60412D03*
X55412D03*
X50412D03*
X45412D03*
X40412D03*
X35412D03*
X30412D03*
X25412D03*
X20412D03*
X15412D03*
X10412D03*
X6000Y6588D03*
Y11588D03*
Y16588D03*
Y21588D03*
Y26588D03*
Y31588D03*
Y36588D03*
Y41588D03*
Y46588D03*
Y51588D03*
Y56588D03*
Y61588D03*
Y66588D03*
Y71588D03*
Y76588D03*
Y81588D03*
Y86588D03*
Y91588D03*
Y96588D03*
Y101588D03*
Y106588D03*
Y111588D03*
Y116588D03*
Y121588D03*
Y126588D03*
Y131588D03*
Y136588D03*
Y141588D03*
Y146588D03*
Y151588D03*
Y156588D03*
Y161588D03*
Y166588D03*
Y171588D03*
Y176588D03*
Y181588D03*
Y186588D03*
Y191588D03*
Y196588D03*
Y201588D03*
Y206588D03*
Y211588D03*
Y216588D03*
Y221588D03*
Y226588D03*
Y231588D03*
Y236588D03*
Y241588D03*
Y246588D03*
Y251588D03*
Y256588D03*
Y261588D03*
Y266588D03*
Y271588D03*
Y276588D03*
Y281588D03*
Y286588D03*
Y291588D03*
Y296588D03*
Y301588D03*
Y306588D03*
Y311588D03*
Y316588D03*
Y321588D03*
Y326588D03*
Y331588D03*
Y336588D03*
Y341588D03*
Y346588D03*
Y351588D03*
Y356588D03*
Y361588D03*
Y366588D03*
Y371588D03*
Y376588D03*
Y441588D03*
Y436588D03*
Y431588D03*
Y426588D03*
Y421588D03*
Y416588D03*
Y411588D03*
Y406588D03*
Y386588D03*
Y391588D03*
Y396588D03*
Y401588D03*
Y446588D03*
Y451588D03*
Y456588D03*
Y461588D03*
Y381588D03*
Y466588D03*
Y471588D03*
Y476588D03*
Y481588D03*
Y486588D03*
Y491588D03*
Y496588D03*
Y501588D03*
Y506588D03*
Y511588D03*
Y516588D03*
Y521588D03*
Y526588D03*
Y531588D03*
Y536588D03*
Y541588D03*
Y546588D03*
Y551588D03*
Y556588D03*
Y561588D03*
Y566588D03*
Y571588D03*
Y576588D03*
Y581588D03*
Y586588D03*
Y591588D03*
Y596588D03*
Y601588D03*
Y606588D03*
Y611588D03*
Y616588D03*
Y621588D03*
Y626588D03*
Y631588D03*
Y636588D03*
Y641588D03*
Y646588D03*
Y651588D03*
Y656588D03*
Y661588D03*
Y666588D03*
Y671588D03*
Y676588D03*
Y681588D03*
Y686588D03*
Y691588D03*
Y696588D03*
Y701588D03*
Y706588D03*
Y711588D03*
Y716588D03*
Y721588D03*
Y726588D03*
Y731588D03*
Y736588D03*
Y741588D03*
Y746588D03*
Y751588D03*
Y756588D03*
Y761588D03*
Y766588D03*
Y771588D03*
Y776588D03*
Y781588D03*
Y786588D03*
Y791588D03*
Y796588D03*
Y801588D03*
Y806588D03*
Y811588D03*
Y816588D03*
Y821588D03*
Y826588D03*
Y831588D03*
Y836588D03*
Y841588D03*
Y846588D03*
Y851588D03*
Y856588D03*
Y861588D03*
Y866588D03*
Y871588D03*
Y876588D03*
Y881588D03*
Y886588D03*
Y891588D03*
Y896588D03*
Y901588D03*
Y906588D03*
Y911588D03*
Y916588D03*
Y921588D03*
Y926588D03*
Y931588D03*
Y936588D03*
Y941588D03*
Y946588D03*
Y951588D03*
X26300Y873700D03*
Y864100D03*
Y868900D03*
X21500Y873700D03*
Y864100D03*
Y868900D03*
X6000Y956588D03*
Y961588D03*
Y966588D03*
Y971588D03*
Y976588D03*
Y981588D03*
Y986588D03*
Y991588D03*
Y996588D03*
Y1001588D03*
Y1006588D03*
Y1011588D03*
Y1016588D03*
Y1021588D03*
Y1026588D03*
Y1031588D03*
Y1036588D03*
Y1041588D03*
Y1046588D03*
Y1051588D03*
Y1056588D03*
Y1061588D03*
Y1066588D03*
Y1071588D03*
Y1076588D03*
Y1081588D03*
Y1086588D03*
Y1091588D03*
Y1096588D03*
Y1101588D03*
Y1106588D03*
Y1111588D03*
Y1116588D03*
Y1121588D03*
Y1126588D03*
Y1131588D03*
Y1136588D03*
Y1141588D03*
Y1146588D03*
Y1151588D03*
Y1156588D03*
Y1161588D03*
Y1166588D03*
Y1171588D03*
Y1176588D03*
Y1181588D03*
Y1186588D03*
Y1191588D03*
Y1196588D03*
Y1201588D03*
Y1206588D03*
Y1211588D03*
Y1216588D03*
Y1221588D03*
Y1226588D03*
Y1231588D03*
Y1236588D03*
Y1321588D03*
Y1326588D03*
Y1331588D03*
Y1286588D03*
Y1291588D03*
Y1296588D03*
Y1301588D03*
Y1306588D03*
Y1311588D03*
Y1316588D03*
Y1241588D03*
Y1246588D03*
Y1251588D03*
Y1256588D03*
Y1261588D03*
Y1266588D03*
Y1271588D03*
Y1276588D03*
Y1281588D03*
Y1421588D03*
Y1416588D03*
Y1411588D03*
Y1406588D03*
Y1401588D03*
Y1396588D03*
Y1391588D03*
Y1386588D03*
Y1381588D03*
Y1376588D03*
Y1371588D03*
Y1366588D03*
Y1361588D03*
Y1356588D03*
Y1351588D03*
Y1346588D03*
Y1341588D03*
Y1426588D03*
Y1336588D03*
Y1451588D03*
Y1446588D03*
Y1441588D03*
Y1436588D03*
Y1431588D03*
X99000Y1501000D03*
X61500Y1502000D03*
X87539Y1499118D03*
X82539D03*
X77539D03*
X72539D03*
X67539D03*
X92539D03*
X11000Y1455500D03*
X15500Y1458500D03*
X17811Y1462693D03*
Y1467693D03*
Y1472693D03*
Y1477693D03*
Y1482693D03*
Y1487693D03*
Y1492693D03*
Y1497693D03*
Y1502693D03*
Y1507693D03*
X17500Y1512000D03*
X21819Y1513685D03*
X26819D03*
X31819D03*
X36819D03*
X41819D03*
X46819D03*
X51819D03*
X56819D03*
X58500Y1508000D03*
X195412Y6000D03*
X190412D03*
X185412D03*
X180412D03*
X175412D03*
X170412D03*
X165412D03*
X160412D03*
X155412D03*
X150412D03*
X145412D03*
X140412D03*
X135412D03*
X130412D03*
X125412D03*
X120412D03*
X115412D03*
X110412D03*
X105412D03*
X127600Y437500D03*
Y432700D03*
X122800Y437500D03*
Y432700D03*
X127600Y427900D03*
X122800D03*
X169215Y876085D03*
Y880885D03*
X154215D03*
Y876085D03*
X169215Y895685D03*
Y890885D03*
X154215Y895685D03*
Y890885D03*
X164200Y885700D03*
X158900D03*
X192963Y888625D03*
Y883625D03*
X188163Y888625D03*
X183363D03*
X178563D03*
Y883625D03*
X173763D03*
Y888625D03*
X183363Y883625D03*
X188163D03*
X113363Y884925D03*
X180000Y1424000D03*
Y1430000D03*
X186000Y1424000D03*
Y1430000D03*
X152000Y1377000D03*
Y1383000D03*
X158000Y1377000D03*
Y1383000D03*
X170000D03*
Y1377000D03*
X164000Y1383000D03*
Y1377000D03*
X102000Y1505500D03*
X177433Y1513685D03*
X182433D03*
X187433D03*
X192433D03*
X147433D03*
X152433D03*
X157433D03*
X162433D03*
X167433D03*
X172433D03*
X103000Y1511000D03*
X107433Y1513685D03*
X112433D03*
X117433D03*
X122433D03*
X127433D03*
X132433D03*
X137433D03*
X142433D03*
X290412Y6000D03*
X285412D03*
X280412D03*
X275412D03*
X270412D03*
X265412D03*
X260412D03*
X255412D03*
X250412D03*
X245412D03*
X240412D03*
X235412D03*
X230412D03*
X225412D03*
X220412D03*
X215412D03*
X210412D03*
X205412D03*
X200412D03*
X251200Y457900D03*
Y438300D03*
Y443100D03*
Y453100D03*
X291500Y451100D03*
Y446100D03*
X286700D03*
Y451100D03*
X281900D03*
Y446100D03*
X272300D03*
Y451100D03*
X277100Y446100D03*
Y451100D03*
X267752Y458160D03*
Y438560D03*
Y443360D03*
Y453360D03*
X257127Y448364D03*
X261927D03*
X211590Y427289D03*
X211190Y447189D03*
X197763Y888625D03*
Y883625D03*
X233074Y1429500D03*
X239274Y1429600D03*
X237235Y1419039D03*
X236974Y1425000D03*
X283000Y1492000D03*
X279000Y1498500D03*
X197433Y1513685D03*
X202433D03*
X207433D03*
X212433D03*
X217433D03*
X222433D03*
X227433D03*
X232433D03*
X237433D03*
X242433D03*
X247433D03*
X252433D03*
X257433D03*
X262433D03*
X267433D03*
X272433D03*
X277433D03*
X278646Y1509398D03*
Y1504398D03*
X288685Y1490063D03*
X385412Y6000D03*
X380412D03*
X375412D03*
X370412D03*
X365412D03*
X360412D03*
X355412D03*
X350412D03*
X345412D03*
X340412D03*
X335412D03*
X330412D03*
X325412D03*
X320412D03*
X315412D03*
X310412D03*
X305412D03*
X300412D03*
X295412D03*
X296300Y446100D03*
Y451100D03*
X380780Y1428599D03*
Y1422599D03*
Y1416599D03*
Y1410599D03*
X374780Y1428599D03*
Y1422599D03*
Y1416599D03*
Y1410599D03*
X293685Y1490063D03*
X298685D03*
X303685D03*
X308685D03*
X313685D03*
X318685D03*
X323685D03*
X328685D03*
X333685D03*
X338685D03*
X343685D03*
X348685D03*
X353685D03*
X358685D03*
X363685D03*
X368685D03*
X373685D03*
X378685D03*
X383685D03*
X380780Y1434599D03*
X374780D03*
X480412Y6000D03*
X475412D03*
X470412D03*
X465412D03*
X460412D03*
X455412D03*
X450412D03*
X445412D03*
X440412D03*
X435412D03*
X430412D03*
X425412D03*
X420412D03*
X415412D03*
X410412D03*
X405412D03*
X400412D03*
X395412D03*
X390412D03*
X388685Y1490063D03*
X393685D03*
X398685D03*
X403685D03*
X408685D03*
X413685D03*
X418685D03*
X423685D03*
X428685D03*
X433685D03*
X438685D03*
X443685D03*
X448685D03*
X453685D03*
X458685D03*
X463685D03*
X468685D03*
X473685D03*
X478685D03*
X575412Y6000D03*
X570412D03*
X565412D03*
X560412D03*
X555412D03*
X550412D03*
X545412D03*
X540412D03*
X535412D03*
X530412D03*
X525412D03*
X520412D03*
X515412D03*
X510412D03*
X505412D03*
X500412D03*
X495412D03*
X490412D03*
X485412D03*
X501000Y1494000D03*
X503000Y1499000D03*
X494500Y1490500D03*
X574937Y1513685D03*
X569937D03*
X564937D03*
X559937D03*
X554937D03*
X549937D03*
X544937D03*
X539937D03*
X534937D03*
X529937D03*
X524937D03*
X483685Y1490063D03*
X488685D03*
X503244Y1504378D03*
Y1509378D03*
X504937Y1513685D03*
X509937D03*
X514937D03*
X519937D03*
X513917Y1447297D03*
X507917D03*
X519717D03*
X670412Y6000D03*
X665412D03*
X660412D03*
X655412D03*
X650412D03*
X645412D03*
X640412D03*
X635412D03*
X630412D03*
X625412D03*
X620412D03*
X615412D03*
X610412D03*
X605412D03*
X600412D03*
X595412D03*
X590412D03*
X585412D03*
X580412D03*
X669937Y1513685D03*
X659937D03*
X654937D03*
X649937D03*
X644937D03*
X639937D03*
X634937D03*
X629937D03*
X624937D03*
X619937D03*
X614937D03*
X609937D03*
X604937D03*
X599937D03*
X594937D03*
X589937D03*
X584937D03*
X579937D03*
X664937D03*
X765412Y6000D03*
X760412D03*
X755412D03*
X750412D03*
X745412D03*
X740412D03*
X735412D03*
X730412D03*
X725412D03*
X720412D03*
X715412D03*
X710412D03*
X705412D03*
X700412D03*
X695412D03*
X690412D03*
X685412D03*
X680412D03*
X675412D03*
X722000Y1503500D03*
X718500Y1500000D03*
X680500Y1503500D03*
X674937Y1513685D03*
X688012Y1499118D03*
X693012D03*
X698012D03*
X703012D03*
X708012D03*
X713012D03*
X724000Y1509500D03*
X725551Y1513685D03*
X730551D03*
X735551D03*
X740551D03*
X745551D03*
X750551D03*
X755551D03*
X760551D03*
X765551D03*
X678500Y1510500D03*
X777465Y93947D03*
Y88947D03*
Y83947D03*
Y78947D03*
Y73947D03*
Y68947D03*
Y63947D03*
Y58947D03*
Y53947D03*
Y48947D03*
Y43947D03*
Y38947D03*
Y33947D03*
Y28947D03*
Y23947D03*
Y18947D03*
Y13947D03*
X778000Y9500D03*
X775412Y6000D03*
X770412D03*
X777465Y183947D03*
Y178947D03*
Y173947D03*
Y168947D03*
Y163947D03*
Y158947D03*
Y153947D03*
Y148947D03*
Y143947D03*
Y138947D03*
Y133947D03*
Y128947D03*
Y123947D03*
Y118947D03*
Y113947D03*
Y108947D03*
Y103947D03*
Y98947D03*
X809500Y197500D03*
X805522Y195764D03*
X808961Y201678D03*
Y206678D03*
Y211678D03*
Y216678D03*
Y236678D03*
Y231678D03*
Y226678D03*
Y221678D03*
Y241678D03*
X779022Y190764D03*
X784022Y194764D03*
X800522Y195764D03*
X795522D03*
X790522D03*
X826843Y409096D03*
Y404296D03*
Y399496D03*
X822043D03*
Y404296D03*
Y409096D03*
X807643Y408996D03*
Y404196D03*
Y399396D03*
X802843D03*
Y404196D03*
Y408996D03*
X826843Y419764D03*
Y424564D03*
Y429364D03*
X802843Y419664D03*
X807643D03*
X822043Y419764D03*
X802843Y429264D03*
Y424464D03*
X807643D03*
Y429264D03*
X822043Y429364D03*
Y424564D03*
X822400Y567100D03*
Y562300D03*
Y557500D03*
X817600D03*
Y562300D03*
Y567100D03*
X803200Y557400D03*
Y562200D03*
Y567000D03*
X798400Y557400D03*
Y562200D03*
Y567000D03*
X822400Y587368D03*
Y582568D03*
X817600D03*
Y587368D03*
X803200Y587268D03*
Y582468D03*
X798400D03*
Y587268D03*
X822400Y577768D03*
X817600D03*
X803200Y577668D03*
X798400D03*
X808300Y1197300D03*
X813100D03*
Y1206900D03*
Y1202100D03*
X808300D03*
Y1206900D03*
X794100Y1197300D03*
X789300D03*
X794100Y1202100D03*
Y1206900D03*
X789300Y1202100D03*
Y1206900D03*
X808300Y1227168D03*
Y1222368D03*
X813100D03*
Y1227168D03*
X794100D03*
Y1222368D03*
X789300D03*
Y1227168D03*
X813100Y1217568D03*
X808300D03*
X789300D03*
X794100D03*
X779500Y1491000D03*
X775000Y1495500D03*
X770551Y1513685D03*
X773528Y1510662D03*
Y1505662D03*
Y1500662D03*
X786803Y1490063D03*
X791803D03*
X796803D03*
X801803D03*
X806803D03*
X811803D03*
X816803D03*
X821803D03*
X826803D03*
X831803D03*
X836803D03*
X841803D03*
X846803D03*
X851803D03*
X856803D03*
X861803D03*
X887127Y254031D03*
X944200Y1083100D03*
X938900Y1103700D03*
X938800Y1109300D03*
X945200Y1398300D03*
Y1393500D03*
X950200Y1394500D03*
X866803Y1490063D03*
X871803D03*
X876803D03*
X881803D03*
X886803D03*
X891803D03*
X896803D03*
X901803D03*
X906803D03*
X911803D03*
X916803D03*
X921803D03*
X926803D03*
X931803D03*
X936803D03*
X941803D03*
X946803D03*
X951803D03*
X956803D03*
X1012000Y371369D03*
X1015537Y365911D03*
X1038200Y762300D03*
X1021194Y766883D03*
X1035594Y766983D03*
X1040394D03*
X1021194Y771683D03*
Y776483D03*
X1035594Y776583D03*
Y771783D03*
X1040394D03*
Y776583D03*
X1016394Y766883D03*
Y776483D03*
Y771683D03*
X997000Y1496000D03*
X993000Y1491500D03*
X961803Y1490063D03*
X966803D03*
X971803D03*
X976803D03*
X981803D03*
X986803D03*
X998126Y1503614D03*
Y1508614D03*
Y1513614D03*
X1003126D03*
X1008126D03*
X1013126D03*
X1018126D03*
X1023126D03*
X1028126D03*
X1033126D03*
X1038126D03*
X1043126D03*
X1048126D03*
X1053126D03*
X1068734Y195764D03*
X1064500Y197500D03*
X1065055Y201895D03*
Y206895D03*
Y211895D03*
Y216895D03*
Y226895D03*
Y231895D03*
Y236895D03*
Y241895D03*
Y221895D03*
X1148734Y195764D03*
X1143734D03*
X1138734D03*
X1133734D03*
X1128734D03*
X1123734D03*
X1118734D03*
X1113734D03*
X1103734D03*
X1098734D03*
X1093734D03*
X1088734D03*
X1083734D03*
X1078734D03*
X1073734D03*
X1075627Y374973D03*
X1075829Y380885D03*
X1119877Y408072D03*
Y403272D03*
Y398472D03*
X1124677D03*
Y403272D03*
Y408072D03*
X1100677Y407972D03*
Y403172D03*
Y398372D03*
X1105477D03*
Y403172D03*
Y407972D03*
X1119877Y423540D03*
Y428340D03*
Y418740D03*
X1124677Y428340D03*
Y423540D03*
Y418740D03*
X1105477Y428240D03*
Y423440D03*
X1100677D03*
Y428240D03*
X1105477Y418640D03*
X1100677D03*
X1076142Y386839D03*
X1057400Y771600D03*
X1057600Y776500D03*
X1067200Y786500D03*
X1062400D03*
Y781500D03*
X1057600Y786500D03*
Y781500D03*
X1067200Y791500D03*
X1062400D03*
X1067200Y796500D03*
X1062400D03*
X1057600D03*
Y791500D03*
X1128700Y1206500D03*
X1133500D03*
Y1201700D03*
X1128700D03*
X1133500Y1196900D03*
X1128700D03*
X1109600Y1197100D03*
X1114400D03*
X1109600Y1201900D03*
X1114400D03*
Y1206700D03*
X1109600D03*
X1128500Y1225700D03*
X1133300D03*
X1109400Y1221100D03*
X1114200D03*
Y1225900D03*
X1109400D03*
X1133300Y1220900D03*
X1128500D03*
X1133300Y1216100D03*
X1128500D03*
X1109400Y1216300D03*
X1114200D03*
X1087933Y1411323D03*
X1082933D03*
X1077933D03*
X1095567Y1426057D03*
X1117200Y1346700D03*
X1058126Y1513614D03*
X1061675Y1510352D03*
X1065210Y1506817D03*
X1066638Y1472408D03*
Y1467408D03*
Y1462408D03*
Y1457408D03*
Y1452408D03*
Y1447408D03*
Y1442408D03*
X1095567Y1431057D03*
Y1436057D03*
Y1441057D03*
Y1446057D03*
Y1451057D03*
Y1456057D03*
Y1461057D03*
Y1466057D03*
X1096039Y1505861D03*
X1099575Y1509397D03*
X1103110Y1512932D03*
X1107798Y1513685D03*
X1112798D03*
X1117798D03*
X1122798D03*
X1127798D03*
X1132798D03*
X1137798D03*
X1142798D03*
X1147798D03*
X1095567Y1471057D03*
X1066638Y1502408D03*
X1115000Y1485000D03*
X1118000Y1480500D03*
X1112000D03*
X1234500Y6000D03*
X1243844D03*
X1238844D03*
X1230409Y7565D03*
Y12565D03*
Y17565D03*
Y22565D03*
Y27565D03*
Y32565D03*
Y37565D03*
Y42565D03*
Y47565D03*
Y52565D03*
Y57565D03*
Y62565D03*
Y67565D03*
Y72565D03*
Y77565D03*
Y82565D03*
Y87565D03*
Y92565D03*
X1229000Y189500D03*
X1230409Y97565D03*
Y102565D03*
Y107565D03*
Y112565D03*
Y117565D03*
Y122565D03*
Y127565D03*
Y132565D03*
Y137565D03*
Y142565D03*
Y147565D03*
Y152565D03*
Y157565D03*
Y162565D03*
Y167565D03*
Y172565D03*
Y177565D03*
Y182565D03*
X1225000Y194000D03*
X1218734Y195764D03*
X1213734D03*
X1208734D03*
X1203734D03*
X1198734D03*
X1193734D03*
X1188734D03*
X1183734D03*
X1178734D03*
X1173734D03*
X1168734D03*
X1163734D03*
X1158734D03*
X1153734D03*
X1151100Y1179300D03*
X1155900D03*
X1151100Y1184100D03*
X1155900D03*
Y1188900D03*
X1151100D03*
X1245500Y1500500D03*
X1208000Y1502500D03*
X1234783Y1499118D03*
X1229783D03*
X1224783D03*
X1219783D03*
X1214783D03*
X1239783D03*
X1152798Y1513685D03*
X1157798D03*
X1162798D03*
X1167798D03*
X1172798D03*
X1177798D03*
X1182798D03*
X1187798D03*
X1192798D03*
X1197798D03*
X1202798D03*
X1205500Y1509000D03*
X1338844Y6000D03*
X1333844D03*
X1328844D03*
X1323844D03*
X1318844D03*
X1313844D03*
X1308844D03*
X1303844D03*
X1298844D03*
X1293844D03*
X1288844D03*
X1283844D03*
X1278844D03*
X1273844D03*
X1268844D03*
X1263844D03*
X1258844D03*
X1253844D03*
X1248844D03*
X1249000Y1504500D03*
X1328464Y1513685D03*
X1333464D03*
X1338464D03*
X1293464D03*
X1298464D03*
X1303464D03*
X1308464D03*
X1313464D03*
X1318464D03*
X1323464D03*
X1250500Y1510500D03*
X1253464Y1513685D03*
X1258464D03*
X1263464D03*
X1268464D03*
X1273464D03*
X1278464D03*
X1283464D03*
X1288464D03*
X1433844Y6000D03*
X1428844D03*
X1423844D03*
X1418844D03*
X1413844D03*
X1408844D03*
X1403844D03*
X1398844D03*
X1393844D03*
X1388844D03*
X1383844D03*
X1378844D03*
X1373844D03*
X1368844D03*
X1363844D03*
X1358844D03*
X1353844D03*
X1348844D03*
X1343844D03*
X1385474Y1429500D03*
X1380074D03*
X1383374Y1425000D03*
X1383674Y1419000D03*
X1433500Y1490500D03*
X1428500Y1494000D03*
X1403500Y1513500D03*
X1398500D03*
X1363464Y1513685D03*
X1368464D03*
X1373464D03*
X1378464D03*
X1383464D03*
X1388464D03*
X1393464D03*
X1353464D03*
X1358464D03*
X1343464D03*
X1348464D03*
X1408464D03*
X1413464D03*
X1418464D03*
X1423464D03*
X1425890Y1510111D03*
Y1505111D03*
Y1500111D03*
X1528844Y6000D03*
X1523844D03*
X1518844D03*
X1513844D03*
X1508844D03*
X1503844D03*
X1498844D03*
X1493844D03*
X1488844D03*
X1483844D03*
X1478844D03*
X1473844D03*
X1468844D03*
X1463844D03*
X1458844D03*
X1453844D03*
X1448844D03*
X1443844D03*
X1438844D03*
X1439716Y1490063D03*
X1444716D03*
X1449716D03*
X1454716D03*
X1459716D03*
X1464716D03*
X1469716D03*
X1474716D03*
X1479716D03*
X1484716D03*
X1489716D03*
X1494716D03*
X1499716D03*
X1504716D03*
X1509716D03*
X1514716D03*
X1519716D03*
X1524716D03*
X1529716D03*
X1623844Y6000D03*
X1618844D03*
X1613844D03*
X1608844D03*
X1603844D03*
X1598844D03*
X1593844D03*
X1588844D03*
X1583844D03*
X1578844D03*
X1573844D03*
X1568844D03*
X1563844D03*
X1558844D03*
X1553844D03*
X1548844D03*
X1543844D03*
X1538844D03*
X1533844D03*
X1534716Y1490063D03*
X1539716D03*
X1544716D03*
X1549716D03*
X1554716D03*
X1559716D03*
X1564716D03*
X1569716D03*
X1574716D03*
X1579716D03*
X1584716D03*
X1589716D03*
X1594716D03*
X1599716D03*
X1604716D03*
X1609716D03*
X1614716D03*
X1619716D03*
X1624716D03*
X1718844Y6000D03*
X1713844D03*
X1708844D03*
X1703844D03*
X1698844D03*
X1693844D03*
X1688844D03*
X1683844D03*
X1678844D03*
X1673844D03*
X1668844D03*
X1663844D03*
X1658844D03*
X1653844D03*
X1648844D03*
X1643844D03*
X1638844D03*
X1633844D03*
X1628844D03*
X1667359Y434407D03*
Y439207D03*
Y429607D03*
X1662559D03*
Y434407D03*
Y439207D03*
X1649500Y1497500D03*
X1646000Y1492000D03*
X1720968Y1513685D03*
X1715968D03*
X1710968D03*
X1705968D03*
X1700968D03*
X1695968D03*
X1690968D03*
X1685968D03*
X1680968D03*
X1670968D03*
X1675968D03*
X1629716Y1490063D03*
X1634716D03*
X1639716D03*
X1650488Y1504165D03*
Y1509165D03*
X1650968Y1513685D03*
X1655968D03*
X1660968D03*
X1665968D03*
X1813844Y6000D03*
X1808844D03*
X1803844D03*
X1798844D03*
X1793844D03*
X1788844D03*
X1783844D03*
X1778844D03*
X1773844D03*
X1768844D03*
X1763844D03*
X1758844D03*
X1753844D03*
X1748844D03*
X1743844D03*
X1738844D03*
X1733844D03*
X1728844D03*
X1723844D03*
X1814463Y449725D03*
Y454725D03*
X1804900Y451800D03*
X1809915Y461785D03*
Y446985D03*
Y456985D03*
Y442185D03*
X1799600Y451800D03*
X1794915Y461785D03*
Y446985D03*
Y456985D03*
Y442185D03*
X1751774Y430510D03*
X1753959Y450607D03*
X1741159Y873707D03*
X1736359D03*
X1741159Y864107D03*
X1736359D03*
X1741159Y868907D03*
X1736359D03*
X1766526Y1429400D03*
X1760326Y1429500D03*
X1763926Y1419000D03*
X1763626Y1425000D03*
X1786004Y1513500D03*
X1780968Y1513685D03*
X1775968D03*
X1770968D03*
X1765968D03*
X1760968D03*
X1755968D03*
X1750968D03*
X1745968D03*
X1740968D03*
X1796004Y1513500D03*
X1801004D03*
X1806004D03*
X1811004D03*
X1816004D03*
X1730968Y1513685D03*
X1725968D03*
X1791004Y1513500D03*
X1735968Y1513685D03*
X1913844Y6000D03*
X1908844D03*
X1903844D03*
X1898844D03*
X1893844D03*
X1888844D03*
X1883844D03*
X1878844D03*
X1873844D03*
X1868844D03*
X1863844D03*
X1858844D03*
X1853844D03*
X1848844D03*
X1843844D03*
X1838844D03*
X1833844D03*
X1828844D03*
X1823844D03*
X1818844D03*
X1838463Y454725D03*
Y449725D03*
X1819263D03*
Y454725D03*
X1833663D03*
Y449725D03*
X1828863D03*
Y454725D03*
X1824063D03*
Y449725D03*
X1912663Y888925D03*
Y883925D03*
X1869115Y876385D03*
Y891185D03*
Y881185D03*
Y895985D03*
X1873800Y886300D03*
X1884115Y876385D03*
X1898263Y883925D03*
Y888925D03*
X1903063D03*
Y883925D03*
X1907863D03*
Y888925D03*
X1884115Y891185D03*
Y881185D03*
Y895985D03*
X1893463Y888925D03*
Y883925D03*
X1879100Y886300D03*
X1888663Y888925D03*
Y883925D03*
X1828363Y884925D03*
X1869500Y1503500D03*
X1865500Y1500000D03*
X1829500Y1501500D03*
X1826500Y1506500D03*
X1855256Y1499118D03*
X1850256D03*
X1845256D03*
X1840256D03*
X1826040Y1513315D03*
X1821040D03*
X1835256Y1499118D03*
X1860256D03*
X1871157Y1509110D03*
X1871582Y1513685D03*
X1876582D03*
X1881582D03*
X1886582D03*
X1891582D03*
X1896582D03*
X1901582D03*
X1906582D03*
X1911582D03*
X1928843Y8985D03*
Y93985D03*
Y88985D03*
Y83985D03*
Y78985D03*
Y73985D03*
Y68985D03*
Y63985D03*
Y58985D03*
Y53985D03*
Y48985D03*
Y43985D03*
Y38985D03*
Y28985D03*
Y23985D03*
Y18985D03*
Y13985D03*
Y33985D03*
X1923844Y6000D03*
X1918844D03*
X1928843Y98985D03*
Y188985D03*
Y183985D03*
Y178985D03*
Y173985D03*
Y168985D03*
Y163985D03*
Y158985D03*
Y153985D03*
Y148985D03*
Y143985D03*
Y138985D03*
Y133985D03*
Y128985D03*
Y123985D03*
Y118985D03*
Y113985D03*
Y108985D03*
Y103985D03*
Y283985D03*
Y278985D03*
Y273985D03*
Y268985D03*
Y263985D03*
Y258985D03*
Y253985D03*
Y248985D03*
Y243985D03*
Y238985D03*
Y233985D03*
Y228985D03*
Y223985D03*
Y218985D03*
Y213985D03*
Y208985D03*
Y203985D03*
Y198985D03*
Y193985D03*
Y378985D03*
Y373985D03*
Y368985D03*
Y363985D03*
Y358985D03*
Y353985D03*
Y348985D03*
Y343985D03*
Y338985D03*
Y333985D03*
Y328985D03*
Y323985D03*
Y318985D03*
Y313985D03*
Y308985D03*
Y303985D03*
Y298985D03*
Y293985D03*
Y288985D03*
Y418985D03*
Y433985D03*
Y428985D03*
Y423985D03*
Y473985D03*
Y468985D03*
Y463985D03*
Y458985D03*
Y453985D03*
Y448985D03*
Y443985D03*
Y438985D03*
Y413985D03*
Y408985D03*
Y403985D03*
Y398985D03*
Y393985D03*
Y388985D03*
Y383985D03*
Y568985D03*
Y563985D03*
Y558985D03*
Y553985D03*
Y548985D03*
Y543985D03*
Y538985D03*
Y533985D03*
Y528985D03*
Y523985D03*
Y518985D03*
Y513985D03*
Y508985D03*
Y503985D03*
Y498985D03*
Y493985D03*
Y488985D03*
Y483985D03*
Y478985D03*
Y663985D03*
Y658985D03*
Y653985D03*
Y648985D03*
Y643985D03*
Y638985D03*
Y633985D03*
Y628985D03*
Y623985D03*
Y618985D03*
Y613985D03*
Y608985D03*
Y603985D03*
Y598985D03*
Y593985D03*
Y588985D03*
Y583985D03*
Y578985D03*
Y573985D03*
Y758985D03*
Y753985D03*
Y748985D03*
Y743985D03*
Y738985D03*
Y733985D03*
Y728985D03*
Y723985D03*
Y718985D03*
Y713985D03*
Y708985D03*
Y703985D03*
Y698985D03*
Y693985D03*
Y688985D03*
Y683985D03*
Y678985D03*
Y673985D03*
Y668985D03*
Y853985D03*
Y848985D03*
Y843985D03*
Y838985D03*
Y833985D03*
Y828985D03*
Y823985D03*
Y818985D03*
Y813985D03*
Y808985D03*
Y803985D03*
Y798985D03*
Y793985D03*
Y788985D03*
Y783985D03*
Y778985D03*
Y773985D03*
Y768985D03*
Y763985D03*
Y918985D03*
Y913985D03*
Y908985D03*
Y903985D03*
Y898985D03*
Y893985D03*
Y888985D03*
Y883985D03*
Y878985D03*
Y873985D03*
Y868985D03*
Y863985D03*
Y858985D03*
Y948985D03*
Y943985D03*
Y938985D03*
Y933985D03*
Y928985D03*
Y923985D03*
Y1043985D03*
Y1038985D03*
Y1033985D03*
Y1028985D03*
Y1023985D03*
Y1018985D03*
Y1013985D03*
Y1008985D03*
Y1003985D03*
Y998985D03*
Y993985D03*
Y988985D03*
Y983985D03*
Y978985D03*
Y973985D03*
Y968985D03*
Y963985D03*
Y958985D03*
Y953985D03*
Y1143985D03*
Y1138985D03*
Y1133985D03*
Y1128985D03*
Y1123985D03*
Y1118985D03*
Y1113985D03*
Y1108985D03*
Y1103985D03*
Y1098985D03*
Y1093985D03*
Y1088985D03*
Y1083985D03*
Y1078985D03*
Y1073985D03*
Y1068985D03*
Y1063985D03*
Y1058985D03*
Y1053985D03*
Y1048985D03*
Y1238985D03*
Y1233985D03*
Y1228985D03*
Y1223985D03*
Y1218985D03*
Y1213985D03*
Y1208985D03*
Y1203985D03*
Y1198985D03*
Y1193985D03*
Y1188985D03*
Y1183985D03*
Y1178985D03*
Y1173985D03*
Y1168985D03*
Y1163985D03*
Y1158985D03*
Y1153985D03*
Y1148985D03*
Y1288985D03*
Y1293985D03*
Y1298985D03*
Y1303985D03*
Y1308985D03*
Y1313985D03*
Y1318985D03*
Y1323985D03*
Y1328985D03*
Y1333985D03*
Y1283985D03*
Y1278985D03*
Y1273985D03*
Y1268985D03*
Y1263985D03*
Y1258985D03*
Y1253985D03*
Y1248985D03*
Y1243985D03*
Y1348985D03*
Y1353985D03*
Y1358985D03*
Y1363985D03*
Y1368985D03*
Y1373985D03*
Y1378985D03*
Y1383985D03*
Y1388985D03*
Y1393985D03*
Y1398985D03*
Y1403985D03*
Y1408985D03*
Y1413985D03*
Y1418985D03*
Y1423985D03*
Y1428985D03*
Y1338985D03*
Y1343985D03*
Y1448985D03*
Y1443985D03*
Y1433985D03*
Y1438985D03*
X1920000Y1458000D03*
X1917500Y1463500D03*
X1916582Y1513685D03*
X1917031Y1509134D03*
Y1504134D03*
Y1499134D03*
Y1494134D03*
Y1489134D03*
Y1484134D03*
Y1479134D03*
Y1474134D03*
Y1469134D03*
X1926500Y1455000D03*
G54D13*
X62263Y877225D03*
X160090Y439489D03*
X1702859Y442907D03*
X1777263Y877225D03*
G54D40*
X161800Y853585D03*
Y878385D03*
Y917685D03*
Y892885D03*
X259627Y416249D03*
Y441049D03*
Y455549D03*
Y480349D03*
X1802496Y458967D03*
Y419667D03*
Y444467D03*
Y483767D03*
X1876600Y854185D03*
Y918285D03*
Y893485D03*
Y878985D03*
G54D22*
X59963Y887525D03*
X157790Y449789D03*
X1021763Y1114199D03*
X996700Y1099000D03*
X978700Y1126800D03*
X1700559Y453207D03*
X1774963Y887525D03*
G54D31*
X47329Y895302D03*
X48763Y900772D03*
X140716Y453101D03*
X146590Y463036D03*
X192425Y869073D03*
X126263Y914025D03*
X103263Y909525D03*
X112763Y912025D03*
X120496Y1405549D03*
X125469Y1373872D03*
X200879Y470744D03*
X213590Y474289D03*
X224090Y476289D03*
X201778Y878425D03*
X279700Y1428000D03*
X291450Y439719D03*
X298690Y441316D03*
X296183Y433389D03*
X298486Y454996D03*
X462000Y1382985D03*
Y1372985D03*
Y1362985D03*
X474000Y1382985D03*
Y1372985D03*
Y1362985D03*
X426000D03*
X450000Y1372985D03*
Y1382985D03*
X414000Y1372985D03*
X450000Y1362985D03*
X438000Y1372985D03*
X414000Y1362985D03*
X438000D03*
X426000Y1372985D03*
X438000Y1382985D03*
X414000D03*
X426000D03*
X498000Y1332985D03*
X510000Y1344485D03*
X498000Y1352985D03*
X522000Y1344485D03*
X498000Y1342985D03*
X510000Y1354485D03*
X522000D03*
X510000Y1364485D03*
X522000D03*
X510000Y1374485D03*
Y1384485D03*
X522000Y1374485D03*
Y1384485D03*
X498000Y1382985D03*
Y1372985D03*
X486000Y1382985D03*
Y1372985D03*
X498000Y1362985D03*
X486000D03*
X508196Y1434276D03*
X508099Y1439755D03*
X646102Y1321750D03*
X641102D03*
X658200Y1329200D03*
X666100D03*
X581800Y1321200D03*
Y1329100D03*
X589700D03*
Y1321200D03*
X594800Y1313500D03*
X597600Y1321200D03*
Y1329100D03*
X610600Y1313500D03*
Y1305600D03*
Y1297600D03*
X602700Y1313500D03*
Y1305600D03*
Y1297600D03*
X629200Y1329100D03*
X605500Y1321200D03*
X613400D03*
X605500Y1329100D03*
X613400D03*
X621300D03*
X646200Y1420576D03*
X641200D03*
X666100Y1360800D03*
Y1368700D03*
Y1376600D03*
Y1352900D03*
X658200Y1360800D03*
Y1368700D03*
Y1376600D03*
Y1352900D03*
X666100Y1337100D03*
Y1345000D03*
X658200Y1337100D03*
Y1345000D03*
X581800Y1376500D03*
Y1384400D03*
Y1392300D03*
Y1360700D03*
Y1368600D03*
Y1352800D03*
Y1344900D03*
Y1337000D03*
X589700Y1392300D03*
Y1400200D03*
Y1344900D03*
Y1352800D03*
Y1384400D03*
Y1376500D03*
Y1368600D03*
Y1360700D03*
Y1337000D03*
X597600Y1400200D03*
Y1408100D03*
Y1360700D03*
Y1368600D03*
Y1392300D03*
Y1376500D03*
Y1384400D03*
Y1352800D03*
Y1337000D03*
Y1344900D03*
X629200D03*
X621300D03*
X613400D03*
X605500D03*
Y1360700D03*
X613400D03*
X621300D03*
X629200D03*
X605500Y1352800D03*
X613400D03*
X621300D03*
X629200D03*
Y1368600D03*
Y1376500D03*
X605500Y1408100D03*
Y1400200D03*
Y1392300D03*
Y1384400D03*
Y1376500D03*
Y1368600D03*
X613400Y1400200D03*
Y1392300D03*
Y1384400D03*
Y1376500D03*
Y1368600D03*
X621300Y1376500D03*
Y1368600D03*
X629200Y1337000D03*
X613400D03*
X621300D03*
X605500D03*
X613400Y1408100D03*
X665700Y1463500D03*
Y1468500D03*
Y1458000D03*
Y1453000D03*
X705600Y1329200D03*
X697700Y1321300D03*
Y1329200D03*
X689800D03*
Y1321300D03*
X693800Y1313900D03*
Y1306000D03*
X685900D03*
X678000D03*
Y1313900D03*
X685900D03*
X681900Y1321300D03*
X674000D03*
Y1329200D03*
X681900D03*
X693800Y1298000D03*
X685900D03*
X678000D03*
X768867Y1311110D03*
Y1335110D03*
Y1327110D03*
Y1319110D03*
X705600Y1337100D03*
Y1360800D03*
Y1352900D03*
Y1345000D03*
Y1376600D03*
Y1368700D03*
X699600Y1408200D03*
Y1392400D03*
Y1400300D03*
X697700Y1345000D03*
Y1360800D03*
Y1368700D03*
Y1376600D03*
X697100Y1384600D03*
X697700Y1352900D03*
Y1337100D03*
X691700Y1408200D03*
Y1400300D03*
X675900D03*
X683800D03*
Y1408200D03*
X675900D03*
X689800Y1352900D03*
Y1384500D03*
Y1376600D03*
X691700Y1392400D03*
X689800Y1368700D03*
Y1360800D03*
X674000D03*
X681900D03*
Y1368700D03*
X674000D03*
X675900Y1392400D03*
X683800D03*
X674000Y1376600D03*
X681900D03*
Y1384500D03*
X674000D03*
Y1352900D03*
X681900D03*
X689800Y1345000D03*
Y1337100D03*
X681900D03*
X674000D03*
X681900Y1345000D03*
X674000D03*
X768867Y1383110D03*
Y1359110D03*
Y1367110D03*
Y1351110D03*
Y1343110D03*
Y1391110D03*
Y1399110D03*
Y1375110D03*
X858500Y845700D03*
X858100Y850000D03*
X848300Y847700D03*
X844800Y895902D03*
X845732Y891713D03*
X847881Y1198981D03*
X810000Y1290500D03*
X786200Y1334100D03*
X794200D03*
X801000Y1333800D03*
X786200Y1326100D03*
X794200D03*
X776867Y1311110D03*
Y1335110D03*
Y1327110D03*
Y1319110D03*
X775600Y1302400D03*
X801000Y1325800D03*
X790056Y1297863D03*
X798056D03*
X782056D03*
X834000Y1324500D03*
Y1317500D03*
Y1310500D03*
Y1303500D03*
X827000D03*
X820000D03*
X827000Y1310500D03*
X820000D03*
X827000Y1317500D03*
X820000D03*
X827000Y1324500D03*
X820000D03*
X810221Y1339832D03*
X810000Y1377500D03*
X776867Y1399110D03*
X790330Y1407929D03*
X782330D03*
X798330D03*
X795000Y1377900D03*
X786600Y1378100D03*
X790950Y1372703D03*
X776867Y1383110D03*
Y1359110D03*
X782950Y1372703D03*
X776867Y1367110D03*
Y1375110D03*
X798950Y1372703D03*
X776867Y1391110D03*
X790223Y1339930D03*
X782223Y1339430D03*
X798223Y1339930D03*
X776867Y1351110D03*
Y1343110D03*
X834000Y1386000D03*
Y1379000D03*
Y1363000D03*
Y1356000D03*
Y1349000D03*
Y1342000D03*
X827000D03*
X820000D03*
X827000Y1349000D03*
X820000D03*
X827000Y1356000D03*
X820000D03*
X827000Y1363000D03*
X820000D03*
X827000Y1379000D03*
X820000D03*
X827000Y1386000D03*
X820000D03*
X827000Y1393000D03*
X820000D03*
X943904Y372485D03*
X896476Y502611D03*
X913276Y501747D03*
X950000Y1081000D03*
X941456Y1182512D03*
X951723Y1177569D03*
X873200Y1208700D03*
X942100Y1193300D03*
X958200Y1303900D03*
X942400D03*
X950300D03*
X934500D03*
X926600D03*
X958200Y1311800D03*
X926600D03*
X934500D03*
X950300D03*
X942400D03*
X903500Y1319400D03*
X950300Y1319700D03*
X958200D03*
X934500D03*
X942400D03*
X926600D03*
X918700D03*
X910800D03*
X887800Y1327100D03*
X934700Y1327500D03*
X895200D03*
X903100D03*
X911000D03*
X926800D03*
X918900D03*
X887800Y1335000D03*
X914031Y1243291D03*
X941559Y1408198D03*
Y1403198D03*
X886400Y1368100D03*
Y1376000D03*
X894300D03*
Y1368100D03*
X934700Y1335400D03*
X926800D03*
X918900D03*
X895200D03*
X903100D03*
X911000D03*
X890400Y1358900D03*
X887800Y1350800D03*
Y1342900D03*
X937300Y1359300D03*
X934700Y1343300D03*
Y1351200D03*
X926800Y1343300D03*
Y1351200D03*
X929400Y1359300D03*
X918900Y1343300D03*
Y1351200D03*
X921500Y1359300D03*
X918000Y1368100D03*
Y1376000D03*
X910100Y1368100D03*
Y1376000D03*
X911000Y1343300D03*
Y1351200D03*
X913600Y1359300D03*
X903100Y1343300D03*
Y1351200D03*
X905700Y1359300D03*
X902200Y1376000D03*
Y1368100D03*
X897800Y1359300D03*
X895200Y1351200D03*
Y1343300D03*
X1038179Y413863D03*
X1022646Y401202D03*
X1021469Y390508D03*
X1047434Y429008D03*
X977047Y393217D03*
X996452Y404314D03*
X1027862Y414122D03*
X1004412Y559568D03*
X995316Y554256D03*
X978415Y547627D03*
X968979Y542300D03*
X970000Y1121500D03*
X1000000Y1094500D03*
X973500Y1080500D03*
X1013000Y1108500D03*
X978500Y1122000D03*
X990200Y1118300D03*
X988800Y1126800D03*
X1017700Y1118304D03*
X996900Y1124500D03*
X1016300Y1113500D03*
X982227Y1150350D03*
X998600Y1300900D03*
X991500Y1312100D03*
X1020800Y1300400D03*
X991455Y1320416D03*
X996400Y1315900D03*
X996200Y1307800D03*
X1014000Y1300600D03*
X991755Y1327716D03*
X996055Y1324116D03*
X1007100Y1301100D03*
X1011100Y1305300D03*
X1019829Y1306139D03*
X1002700Y1305700D03*
X991800Y1303400D03*
X1000200Y1311700D03*
Y1320500D03*
X1016429Y1333939D03*
X1021829D03*
X1011029D03*
X1005629D03*
X986755Y1323816D03*
X986700Y1307600D03*
X1000200Y1328100D03*
X1050818Y1311189D03*
Y1316589D03*
X1045418Y1321989D03*
X1050818D03*
X1034618Y1311189D03*
X1040018D03*
X1045418D03*
X1040018Y1316589D03*
X1034618D03*
X1040018Y1321989D03*
X1031600Y1335100D03*
X1037200Y1335000D03*
X1034618Y1321989D03*
X966985Y1393900D03*
X961857D03*
X997900Y1335800D03*
X992500D03*
X997900Y1341200D03*
X992500D03*
X997900Y1346600D03*
X992500D03*
X997900Y1352000D03*
X992500D03*
Y1357400D03*
X997900D03*
X989083Y1387764D03*
X989509Y1393422D03*
X994700Y1385000D03*
X999700Y1374500D03*
X989100Y1381700D03*
X994200Y1362700D03*
X1019829Y1389539D03*
X1013692Y1389688D03*
X1019829Y1361739D03*
X1014306Y1361710D03*
X1008870Y1361681D03*
X1003367Y1361655D03*
X1004217Y1389394D03*
X1008298Y1393071D03*
X994400Y1377300D03*
X999930Y1393070D03*
X999800Y1381600D03*
X999900Y1366800D03*
X994300Y1370100D03*
X989200Y1374800D03*
X988900Y1366900D03*
X1034600Y1349600D03*
X1042400Y1349500D03*
X1037540Y1344964D03*
X1034799Y1340183D03*
X1044700Y1335500D03*
X1043300Y1342500D03*
X1048000Y1346100D03*
X1037111Y1372380D03*
X1039988Y1367352D03*
X1044400Y1363100D03*
X1036900Y1362600D03*
X1034380Y1367469D03*
X1031300Y1362700D03*
X1042100Y1377100D03*
X1034300Y1377200D03*
X1047401Y1375084D03*
X1071421Y443932D03*
X1074279Y407249D03*
X1059563Y425123D03*
X1130800Y472900D03*
X1066481Y1327759D03*
X1061081D03*
X1066481Y1333159D03*
X1061081D03*
X1061618Y1316589D03*
X1056218Y1311189D03*
X1061618D03*
X1056218Y1316589D03*
X1060218Y1321989D03*
X1066491Y1319983D03*
X1066407Y1313972D03*
X1110767Y1309112D03*
X1066481Y1338559D03*
X1061081D03*
X1066481Y1343959D03*
X1061081D03*
X1066481Y1376359D03*
Y1349359D03*
Y1354759D03*
Y1360159D03*
Y1365559D03*
Y1370959D03*
X1061081Y1376359D03*
Y1370959D03*
Y1365559D03*
Y1360159D03*
Y1354759D03*
Y1349359D03*
X1156110Y473330D03*
X1152600Y468470D03*
X1184500Y570000D03*
X1177350Y597792D03*
X1198184Y740895D03*
X1192158Y736695D03*
X1197842Y732495D03*
X1192853Y728295D03*
X1198213Y724095D03*
X1192568Y719895D03*
X1185718Y1333821D03*
X1160612Y1401773D03*
X1247682Y1421608D03*
X1688216Y461478D03*
X1689359Y466454D03*
X1817496Y437282D03*
X1743859Y475207D03*
X1766859Y479707D03*
X1754525Y478316D03*
X1762442Y895401D03*
X1763763Y900772D03*
X1825896Y440582D03*
X1835508Y444107D03*
X1835092Y435418D03*
X1907800Y871200D03*
X1841263Y914025D03*
X1827863Y912525D03*
X1818263Y909525D03*
G54D41*
X125056Y909101D03*
X222883Y471365D03*
X950211Y1087648D03*
X993800Y1131000D03*
X1025500Y1122400D03*
X978300Y1084500D03*
X1765652Y474783D03*
X1840056Y909101D03*
G54D23*
X32263Y878825D03*
X132190Y444689D03*
X127141Y904744D03*
X224968Y467008D03*
X969900Y1132600D03*
X1672859Y444507D03*
X1767737Y470426D03*
X1747263Y878825D03*
X1842141Y904744D03*
G54D14*
X62263Y880825D03*
X160090Y443089D03*
X1702859Y446507D03*
X1777263Y880825D03*
G54D50*
X266535Y1320472D03*
X511535D03*
G54D32*
X85000Y885500D03*
X89000D03*
Y881500D03*
X85000D03*
X89000Y877500D03*
X85000D03*
X89000Y889500D03*
X85000D03*
X89000Y893500D03*
X85000D03*
X81166Y892754D03*
Y888754D03*
X178993Y455018D03*
Y451018D03*
X182827Y447764D03*
Y455764D03*
X186827D03*
X182827Y451764D03*
X186827D03*
X182827Y439764D03*
Y443764D03*
X1001687Y1111499D03*
X1721762Y458436D03*
Y454436D03*
X1725596Y447182D03*
X1729596Y443182D03*
X1725596D03*
X1729596Y455182D03*
X1725596D03*
X1729596Y459182D03*
X1725596D03*
Y451182D03*
X1729596Y447182D03*
Y451182D03*
X1796166Y892754D03*
Y888754D03*
X1804000Y885500D03*
Y881500D03*
X1800000Y885500D03*
Y893500D03*
X1804000D03*
X1800000Y889500D03*
X1804000D03*
X1800000Y877500D03*
X1804000D03*
X1800000Y881500D03*
G54D42*
X121456Y909101D03*
X219283Y471365D03*
X946611Y1087648D03*
X990200Y1131000D03*
X1021900Y1122400D03*
X974700Y1084500D03*
X1762052Y474783D03*
X1836456Y909101D03*
G54D60*
X859086Y1290016D03*
Y1300984D03*
X842500Y1404984D03*
Y1394016D03*
X860000Y1404984D03*
Y1394016D03*
X871589Y1290016D03*
Y1300984D03*
X884060Y1290048D03*
Y1301016D03*
X876500Y1404984D03*
Y1394016D03*
G54D15*
X94463Y908025D03*
X192290Y470289D03*
X512746Y1442322D03*
X1735059Y473707D03*
X1809463Y908025D03*
G54D51*
X384055Y1330472D03*
Y1320472D03*
X354055Y1330472D03*
X364055D03*
X354055Y1320472D03*
X364055D03*
X324055Y1330472D03*
X334055D03*
X324055Y1320472D03*
X334055D03*
X304055Y1330472D03*
Y1320472D03*
X294055Y1330472D03*
Y1320472D03*
X384055Y1340472D03*
Y1350472D03*
X354055Y1340472D03*
Y1350472D03*
X364055Y1340472D03*
Y1350472D03*
X324055Y1340472D03*
Y1350472D03*
X334055Y1340472D03*
Y1350472D03*
X304055D03*
Y1340472D03*
X294055Y1350472D03*
Y1340472D03*
X474055Y1330472D03*
X484055D03*
X474055Y1320472D03*
X484055D03*
X444055Y1330472D03*
X454055D03*
X444055Y1320472D03*
X454055D03*
X414055Y1330472D03*
X424055D03*
X414055Y1320472D03*
X424055D03*
X394055Y1330472D03*
Y1320472D03*
X474055Y1340472D03*
Y1350472D03*
X484055Y1340472D03*
Y1350472D03*
X444055Y1340472D03*
Y1350472D03*
X454055Y1340472D03*
Y1350472D03*
X414055Y1340472D03*
Y1350472D03*
X424055Y1340472D03*
Y1350472D03*
X394055Y1340472D03*
Y1350472D03*
G54D33*
X70603Y887495D03*
X168430Y449759D03*
X114563Y904041D03*
X106363Y893425D03*
X102207Y890524D03*
X212390Y466305D03*
X204190Y455689D03*
X200022Y452941D03*
X832417Y459017D03*
X1008739Y1096000D03*
X1028500Y1118601D03*
X965500Y1128000D03*
X1012800Y1122100D03*
X1002671Y1124700D03*
X977643Y1132490D03*
X1007431Y1122900D03*
X1711199Y453177D03*
X1755159Y469723D03*
X1746959Y459107D03*
X1742758Y456059D03*
X1817739Y889758D03*
X1785603Y887495D03*
X1829563Y904041D03*
X1821363Y893425D03*
G54D24*
X32263Y873225D03*
X132190Y439089D03*
X127141Y899144D03*
X224968Y461408D03*
X969900Y1127000D03*
X1672859Y438907D03*
X1767737Y464826D03*
X1747263Y873225D03*
X1842141Y899144D03*
G54D43*
X104226Y904041D03*
X202053Y466305D03*
X1744822Y469723D03*
X1819226Y904041D03*
G54D25*
X56763Y874225D03*
Y881825D03*
X48763Y874225D03*
Y881825D03*
X40763Y874225D03*
Y881825D03*
X154590Y436489D03*
Y444089D03*
X146590Y436489D03*
Y444089D03*
X138590Y436489D03*
Y444089D03*
X175763Y895225D03*
Y902825D03*
X191763Y895225D03*
Y902825D03*
X183763Y895225D03*
Y902825D03*
X273590Y457489D03*
Y465089D03*
X289590Y457489D03*
Y465089D03*
X281590Y457489D03*
Y465089D03*
X944500Y1122200D03*
Y1129800D03*
X952500Y1122200D03*
Y1129800D03*
X960500Y1122200D03*
Y1129800D03*
X1697359Y439907D03*
Y447507D03*
X1689359Y439907D03*
Y447507D03*
X1681359Y439907D03*
Y447507D03*
X1816338Y460823D03*
Y468423D03*
X1771763Y874225D03*
Y881825D03*
X1763763Y874225D03*
Y881825D03*
X1755763Y874225D03*
Y881825D03*
X1831598Y460827D03*
Y468427D03*
X1823987Y460819D03*
Y468419D03*
X1890763Y895225D03*
Y902825D03*
X1906763Y895225D03*
Y902825D03*
X1898763Y895225D03*
Y902825D03*
G54D52*
X503248Y715748D03*
X1673917Y262992D03*
G54D61*
X809631Y1305085D03*
Y1310085D03*
Y1315085D03*
Y1320085D03*
X810101Y1347591D03*
Y1352591D03*
Y1357591D03*
Y1362591D03*
X809880Y1385259D03*
Y1390259D03*
Y1395259D03*
Y1400259D03*
G54D16*
X98063Y908025D03*
X195890Y470289D03*
X516346Y1442322D03*
X1738659Y473707D03*
X1813063Y908025D03*
G54D70*
X1001687Y1111499D03*
G54D34*
X90709Y1485118D03*
X80709D03*
X70709D03*
X711181D03*
X701181D03*
X691181D03*
X1237953D03*
X1227953D03*
X1217953D03*
X1858425D03*
X1848425D03*
X1838425D03*
G54D26*
X64563Y894025D03*
X56963D03*
X32463Y866525D03*
X40063D03*
X162390Y456289D03*
X154790D03*
X133290Y429089D03*
X140890D03*
X711500Y1463600D03*
X719100D03*
X817800Y1333000D03*
X810200D03*
X817800Y1296000D03*
X810200D03*
X817800Y1371500D03*
X810200D03*
X951461Y1093799D03*
X943861D03*
X951300Y1101700D03*
X943700D03*
X951400Y1109600D03*
X943800D03*
X994800Y1136500D03*
X987200D03*
X994800Y1144500D03*
X987200D03*
X960200Y1082500D03*
X967800D03*
X1705159Y459707D03*
X1697559D03*
X1673059Y432207D03*
X1680659D03*
X1779563Y894025D03*
X1771963D03*
X1747463Y866525D03*
X1755063D03*
G54D62*
X962648Y1101699D03*
X984534D03*
G54D71*
X1004640Y1117605D03*
X998734D03*
Y1105393D03*
X1004640D03*
G54D53*
X501699Y1429055D03*
Y1438055D03*
G54D17*
X88941Y905416D03*
X186768Y467680D03*
X121736Y903674D03*
X219563Y465938D03*
X512849Y1438455D03*
X974200Y1130000D03*
X1762332Y469356D03*
X1729537Y471098D03*
X1803941Y905416D03*
X1836736Y903674D03*
G54D35*
X111024Y39508D03*
Y492264D03*
Y945020D03*
X235236Y39508D03*
Y492264D03*
Y945020D03*
X359449Y39508D03*
Y492264D03*
Y945020D03*
X483661Y39508D03*
Y492264D03*
Y945020D03*
X607874Y39508D03*
Y492264D03*
Y945020D03*
X732087Y39508D03*
Y492264D03*
Y945020D03*
X1281693Y39508D03*
Y492264D03*
Y945020D03*
X1405906Y39508D03*
Y492264D03*
Y945020D03*
X1530118Y39508D03*
Y492264D03*
Y945020D03*
X1654331Y39508D03*
Y492264D03*
Y945020D03*
X1778543Y39508D03*
Y492264D03*
Y945020D03*
X1902756Y39508D03*
Y492264D03*
Y945020D03*
G54D44*
X109826Y904041D03*
X207653Y466305D03*
X1750422Y469723D03*
X1824826Y904041D03*
G54D27*
X83163Y904975D03*
X180990Y467239D03*
X1024284Y1102936D03*
X1723759Y470657D03*
X1798163Y904975D03*
G54D36*
X173228Y55118D03*
X421653Y94488D03*
X670078Y55118D03*
X1343701D03*
X1592126Y94488D03*
X1840551Y55118D03*
G54D72*
X1002671Y1117555D03*
X1000703D03*
Y1105443D03*
X1002671D03*
G54D45*
X143111Y874400D03*
X108489D03*
X240938Y436664D03*
X206316D03*
X1783707Y440082D03*
X1749085D03*
X1823489Y874400D03*
X1858111D03*
G54D18*
X88941Y902016D03*
X186768Y464280D03*
X121736Y900274D03*
X219563Y462538D03*
X512849Y1435055D03*
X974200Y1126600D03*
X1762332Y465956D03*
X1729537Y467698D03*
X1803941Y902016D03*
X1836736Y900274D03*
G54D54*
X512799Y1429105D03*
X516674Y1421605D03*
X508924D03*
G54D63*
X974015Y284449D03*
X986614D03*
X1002362D03*
X1014960D03*
X1030709D03*
X1043307D03*
X974015Y261812D03*
X986614D03*
X1002362D03*
X1014960D03*
X1030709D03*
X1043307D03*
X974015Y278544D03*
X1002362D03*
X1030709D03*
X974015Y267717D03*
X1002362D03*
X1030709D03*
X974015Y255906D03*
X1002362D03*
X1030709D03*
X986614Y278544D03*
X1014960D03*
X1043307D03*
X986614Y267717D03*
X1014960D03*
X1043307D03*
X986614Y255906D03*
X1014960D03*
X1043307D03*
X974015Y307087D03*
X986614D03*
X1002362D03*
X1014960D03*
X1030709D03*
X1043307D03*
X974015Y312993D03*
X1002362D03*
X1030709D03*
X974015Y301182D03*
X1002362D03*
X1030709D03*
X974015Y290355D03*
X1002362D03*
X1030709D03*
X986614Y312993D03*
X1014960D03*
X1043307D03*
X986614Y301182D03*
X1014960D03*
X1043307D03*
X986614Y290355D03*
X1014960D03*
X1043307D03*
X1101405Y1120040D03*
X1119633D03*
X1101405Y1132638D03*
X1119633D03*
X1108098Y1120040D03*
X1126326D03*
X1108098Y1132638D03*
X1126326D03*
G54D55*
X516898Y1435021D03*
X1026700Y1130200D03*
X1013231Y1094671D03*
X986500Y1118800D03*
G54D19*
X98000Y904300D03*
X195827Y466564D03*
X662000Y1464000D03*
Y1468000D03*
Y1453500D03*
Y1457500D03*
X1008689Y1092328D03*
X1027687Y1109799D03*
X1738596Y469982D03*
X1812900Y904300D03*
G54D73*
X995581Y1114452D03*
Y1108546D03*
X1007793D03*
Y1114452D03*
G54D46*
X184252Y1445275D03*
Y1466929D03*
X167716Y1445275D03*
Y1466929D03*
X233858Y1445275D03*
Y1466929D03*
X217322Y1445275D03*
Y1466929D03*
X200787Y1445275D03*
Y1466929D03*
X581102Y1445275D03*
Y1466929D03*
X564567Y1445275D03*
Y1466929D03*
X548031Y1445275D03*
Y1466929D03*
X614173Y1445275D03*
Y1466929D03*
X597637Y1445275D03*
Y1466929D03*
X1331496Y1445275D03*
Y1466929D03*
X1314960Y1445275D03*
Y1466929D03*
X1381102Y1445275D03*
Y1466929D03*
X1364566Y1445275D03*
Y1466929D03*
X1348031Y1445275D03*
Y1466929D03*
X1711811Y1445275D03*
Y1466929D03*
X1695275Y1445275D03*
Y1466929D03*
X1761417Y1445275D03*
Y1466929D03*
X1744881Y1445275D03*
Y1466929D03*
X1728346Y1445275D03*
Y1466929D03*
G54D28*
X83163Y902475D03*
X180990Y464739D03*
X1024284Y1100436D03*
X1723759Y468157D03*
X1798163Y902475D03*
G54D64*
X1021393Y1118601D03*
G54D37*
X111024Y188130D03*
Y640886D03*
Y1093642D03*
X235236Y188130D03*
Y640886D03*
Y1093642D03*
X359449Y188130D03*
Y640886D03*
Y1093642D03*
X483661Y188130D03*
Y640886D03*
Y1093642D03*
X607874Y188130D03*
Y640886D03*
Y1093642D03*
X732087Y188130D03*
Y640886D03*
Y1093642D03*
X1281693Y188130D03*
Y640886D03*
Y1093642D03*
X1405906Y188130D03*
Y640886D03*
Y1093642D03*
X1530118Y188130D03*
Y640886D03*
Y1093642D03*
X1654331Y188130D03*
Y640886D03*
Y1093642D03*
X1778543Y188130D03*
Y640886D03*
Y1093642D03*
X1902756Y188130D03*
Y640886D03*
Y1093642D03*
G54D29*
X85000Y885500D03*
X182827Y447764D03*
X1725596Y451182D03*
X1800000Y885500D03*
G54D47*
X167716Y1495669D03*
X233858D03*
X548031D03*
X614173D03*
X1314960D03*
X1381102D03*
X1695275D03*
X1761417D03*
G54D74*
X995631Y1112483D03*
Y1110515D03*
X1007743D03*
Y1112483D03*
G54D38*
X173228Y122047D03*
X670079D03*
X1343701Y122046D03*
X1840551D03*
G54D65*
X1024793Y1118601D03*
G54D56*
X516898Y1438421D03*
X1026700Y1133600D03*
X1013231Y1098071D03*
X986500Y1122200D03*
G54D39*
X131200Y262981D03*
Y715737D03*
Y1168492D03*
X379232Y262981D03*
Y715737D03*
Y1168492D03*
X627263Y262981D03*
Y715737D03*
Y1168492D03*
X747244Y381878D03*
Y814949D03*
X961417Y703925D03*
Y972429D03*
X1181889Y381878D03*
Y972429D03*
X1301870Y262980D03*
Y715737D03*
Y1168492D03*
X1549901Y262981D03*
Y715737D03*
Y1168492D03*
X1797933Y262980D03*
Y715737D03*
Y1168492D03*
G54D75*
X1104528Y1162257D03*
G54D57*
X669470Y1467800D03*
X1022935Y1130078D03*
X1016645Y1106842D03*
G54D66*
X1031000Y1099500D03*
G54D48*
X197263Y898775D03*
Y898275D03*
X295090Y461039D03*
Y460539D03*
X965500Y1125250D03*
Y1124750D03*
X1836637Y464577D03*
Y464077D03*
X1912263Y898775D03*
Y898275D03*
G54D76*
G01X489037Y-206331D02*
X489911Y-205456D01*
X490566Y-203998D01*
X491003Y-201955D01*
X490566Y-200206D01*
X489693Y-199039D01*
X488164Y-198164D01*
X482269D01*
Y-215664D01*
X489474D01*
X491003Y-214498D01*
X491876Y-212747D01*
X492313Y-210706D01*
X491876Y-208664D01*
X490566Y-206914D01*
X489037Y-206331D01*
X482269D01*
G01X501734Y-215664D02*
Y-203998D01*
G01Y-206331D02*
X502826Y-205164D01*
X503918Y-204289D01*
X505446Y-203998D01*
X506537Y-204289D01*
X507848Y-205164D01*
G01X517706Y-220914D02*
X519016Y-221497D01*
X520763Y-220914D01*
X521854Y-219748D01*
X522728Y-218289D01*
X524037Y-213623D01*
X526876Y-203998D01*
G01X519889D02*
X524037Y-213623D01*
G01X543284Y-205456D02*
X541756Y-204289D01*
X540446Y-203998D01*
X538699Y-204581D01*
X537389Y-205747D01*
X536516Y-207789D01*
X536297Y-209831D01*
X536516Y-211873D01*
X537389Y-213623D01*
X538699Y-215081D01*
X540446Y-215664D01*
X541974Y-215081D01*
X543284Y-213914D01*
G01X554016Y-207789D02*
X561003D01*
X560348Y-205747D01*
X559256Y-204581D01*
X557728Y-203998D01*
X556199Y-204289D01*
X554889Y-205164D01*
X554016Y-207206D01*
X553579Y-208956D01*
Y-210706D01*
X554016Y-212456D01*
X555108Y-214206D01*
X556418Y-215372D01*
X557946Y-215664D01*
X559474Y-215081D01*
X561003Y-213331D01*
G01X597094Y-199623D02*
X595784Y-198747D01*
X594256Y-198164D01*
X592509D01*
X590544Y-199039D01*
X589016Y-200497D01*
X587924Y-202248D01*
X587051Y-205164D01*
X586832Y-207789D01*
X587269Y-210414D01*
X587924Y-212164D01*
X589234Y-213914D01*
X590763Y-215081D01*
X592291Y-215664D01*
X593819D01*
X595348Y-215081D01*
X596658Y-214206D01*
X597750Y-213040D01*
G01X613721Y-215664D02*
Y-203998D01*
G01Y-206039D02*
X612848Y-204873D01*
X611537Y-204289D01*
X610009Y-203998D01*
X608481Y-204581D01*
X607171Y-205747D01*
X606297Y-207497D01*
X605861Y-209831D01*
X606297Y-212164D01*
X607171Y-213914D01*
X608481Y-215081D01*
X610009Y-215664D01*
X611537Y-215372D01*
X612848Y-214498D01*
X613721Y-213331D01*
G01X623579Y-215664D02*
Y-203998D01*
G01Y-206914D02*
X624453Y-205456D01*
X625763Y-204289D01*
X627509Y-203998D01*
X629037Y-204289D01*
X630348Y-205456D01*
X631003Y-207497D01*
Y-215664D01*
G01X640206Y-220914D02*
X641516Y-221497D01*
X643263Y-220914D01*
X644354Y-219748D01*
X645228Y-218289D01*
X646537Y-213623D01*
X649376Y-203998D01*
G01X642389D02*
X646537Y-213623D01*
G01X662291Y-215664D02*
X660981Y-215372D01*
X659671Y-214206D01*
X658797Y-212164D01*
X658361Y-209831D01*
X658797Y-207497D01*
X659671Y-205456D01*
X660981Y-204289D01*
X662291Y-203998D01*
X663601Y-204289D01*
X664911Y-205456D01*
X665784Y-207497D01*
X666003Y-209831D01*
X665784Y-212164D01*
X664911Y-214206D01*
X663601Y-215372D01*
X662291Y-215664D01*
G01X676079D02*
Y-203998D01*
G01Y-206914D02*
X676953Y-205456D01*
X678263Y-204289D01*
X680009Y-203998D01*
X681537Y-204289D01*
X682848Y-205456D01*
X683503Y-207497D01*
Y-215664D01*
G01X710424D02*
Y-198164D01*
X715883D01*
X717629Y-199039D01*
X718721Y-200206D01*
X719158Y-202539D01*
X718721Y-204873D01*
X717411Y-206331D01*
X715883Y-207206D01*
X710424D01*
G01X715883D02*
X719158Y-215664D01*
G01X732291Y-216247D02*
X731854Y-215956D01*
Y-215372D01*
X732291Y-215081D01*
X732728Y-215372D01*
Y-215956D01*
X732291Y-216247D01*
G01X744988Y-215664D02*
Y-198164D01*
X749354D01*
X751101Y-199039D01*
X752411Y-200206D01*
X753503Y-201955D01*
X754376Y-203998D01*
X754594Y-206914D01*
X754376Y-209831D01*
X753503Y-211873D01*
X752411Y-213623D01*
X751101Y-214789D01*
X749354Y-215664D01*
X744988D01*
G01X762924D02*
Y-198164D01*
X768164D01*
X769911Y-199039D01*
X771221Y-201081D01*
X771658Y-203414D01*
X771221Y-205747D01*
X770129Y-207497D01*
X768164Y-208373D01*
X762924D01*
G01X786537Y-206331D02*
X787411Y-205456D01*
X788066Y-203998D01*
X788503Y-201955D01*
X788066Y-200206D01*
X787193Y-199039D01*
X785664Y-198164D01*
X779769D01*
Y-215664D01*
X786974D01*
X788503Y-214498D01*
X789376Y-212747D01*
X789813Y-210706D01*
X789376Y-208664D01*
X788066Y-206914D01*
X786537Y-206331D01*
X779769D01*
G01X595364Y-170664D02*
Y-153164D01*
X601041Y-167747D01*
X606718Y-153164D01*
Y-170664D01*
G01X618541D02*
X617231Y-170372D01*
X615921Y-169206D01*
X615047Y-167164D01*
X614611Y-164831D01*
X615047Y-162497D01*
X615921Y-160456D01*
X617231Y-159289D01*
X618541Y-158998D01*
X619851Y-159289D01*
X621161Y-160456D01*
X622034Y-162497D01*
X622253Y-164831D01*
X622034Y-167164D01*
X621161Y-169206D01*
X619851Y-170372D01*
X618541Y-170664D01*
G01X639971Y-153164D02*
Y-170664D01*
G01Y-168040D02*
X639098Y-169498D01*
X637787Y-170372D01*
X636259Y-170664D01*
X634513Y-170081D01*
X633203Y-168623D01*
X632329Y-166873D01*
X632111Y-164831D01*
X632329Y-162789D01*
X633203Y-161039D01*
X634513Y-159581D01*
X636259Y-158998D01*
X637787Y-159289D01*
X638879Y-159873D01*
X639971Y-161039D01*
G01X650266Y-162789D02*
X657253D01*
X656598Y-160747D01*
X655506Y-159581D01*
X653978Y-158998D01*
X652449Y-159289D01*
X651139Y-160164D01*
X650266Y-162206D01*
X649829Y-163956D01*
Y-165706D01*
X650266Y-167456D01*
X651358Y-169206D01*
X652668Y-170372D01*
X654196Y-170664D01*
X655724Y-170081D01*
X657253Y-168331D01*
G01X671041Y-170664D02*
Y-153164D01*
G01X839441Y-215664D02*
Y-198164D01*
X836821Y-201664D01*
G01Y-215664D02*
X842061D01*
G01X852793Y-208373D02*
X854321Y-206331D01*
X855631Y-205164D01*
X857378Y-204581D01*
X858906Y-205164D01*
X859998Y-206331D01*
X860871Y-208081D01*
X861089Y-210122D01*
X860871Y-211873D01*
X859998Y-213623D01*
X858687Y-215081D01*
X857159Y-215664D01*
X855413Y-215081D01*
X853884Y-213331D01*
X853011Y-210706D01*
X852793Y-207789D01*
X853229Y-203998D01*
X853884Y-201955D01*
X854976Y-199914D01*
X856504Y-198456D01*
X858033Y-198164D01*
X859561Y-198747D01*
X860653Y-200206D01*
G01X869638Y-212164D02*
X870947Y-214206D01*
X872694Y-215372D01*
X874659Y-215664D01*
X876406Y-215372D01*
X878153Y-213914D01*
X879244Y-212164D01*
X879463Y-210414D01*
X879026Y-208373D01*
X877498Y-206914D01*
X875969Y-206331D01*
X874004D01*
G01X875969D02*
X877279Y-205456D01*
X878371Y-203998D01*
X878808Y-202248D01*
X878371Y-200497D01*
X877279Y-199039D01*
X875314Y-198164D01*
X873349Y-198456D01*
X871384Y-199623D01*
G01X891941Y-215664D02*
Y-198164D01*
X889321Y-201664D01*
G01Y-215664D02*
X894561D01*
G01X909004D02*
X909441Y-211873D01*
X910096Y-208664D01*
X910969Y-205747D01*
X912061Y-202539D01*
X913808Y-198164D01*
X905074D01*
G01X826324Y-170664D02*
Y-153164D01*
X831564D01*
X833311Y-154039D01*
X834621Y-156081D01*
X835058Y-158414D01*
X834621Y-160747D01*
X833529Y-162497D01*
X831564Y-163373D01*
X826324D01*
G01X852994Y-154623D02*
X851684Y-153747D01*
X850156Y-153164D01*
X848409D01*
X846444Y-154039D01*
X844916Y-155497D01*
X843824Y-157248D01*
X842951Y-160164D01*
X842732Y-162789D01*
X843169Y-165414D01*
X843824Y-167164D01*
X845134Y-168914D01*
X846663Y-170081D01*
X848191Y-170664D01*
X849719D01*
X851248Y-170081D01*
X852558Y-169206D01*
X853650Y-168040D01*
G01X867437Y-161331D02*
X868311Y-160456D01*
X868966Y-158998D01*
X869403Y-156955D01*
X868966Y-155206D01*
X868093Y-154039D01*
X866564Y-153164D01*
X860669D01*
Y-170664D01*
X867874D01*
X869403Y-169498D01*
X870276Y-167747D01*
X870713Y-165706D01*
X870276Y-163664D01*
X868966Y-161914D01*
X867437Y-161331D01*
X860669D01*
G01X876641Y-176497D02*
X889741D01*
G01X895669Y-170664D02*
Y-153164D01*
X905713Y-170664D01*
Y-153164D01*
G01X918191Y-170664D02*
X916444Y-170372D01*
X914916Y-169206D01*
X913606Y-167456D01*
X912732Y-165414D01*
X912296Y-163081D01*
Y-160747D01*
X912732Y-158414D01*
X913606Y-156372D01*
X914916Y-154623D01*
X916444Y-153456D01*
X918191Y-153164D01*
X919937Y-153456D01*
X921466Y-154623D01*
X922776Y-156372D01*
X923650Y-158414D01*
X924086Y-160747D01*
Y-163081D01*
X923650Y-165414D01*
X922776Y-167456D01*
X921466Y-169206D01*
X919937Y-170372D01*
X918191Y-170664D01*
G01X1000741Y-215664D02*
Y-198164D01*
X998121Y-201664D01*
G01Y-215664D02*
X1003361D01*
G01X969032Y-153164D02*
X974491Y-170664D01*
X979950Y-153164D01*
G01X996358Y-170664D02*
X987624D01*
Y-153164D01*
X996358D01*
G01X992864Y-161622D02*
X987624D01*
G01X1005124Y-170664D02*
Y-153164D01*
X1010583D01*
X1012329Y-154039D01*
X1013421Y-155206D01*
X1013858Y-157539D01*
X1013421Y-159873D01*
X1012111Y-161331D01*
X1010583Y-162206D01*
X1005124D01*
G01X1010583D02*
X1013858Y-170664D01*
G01X1026991Y-171247D02*
X1026554Y-170956D01*
Y-170372D01*
X1026991Y-170081D01*
X1027428Y-170372D01*
Y-170956D01*
X1026991Y-171247D01*
G01X1175195Y-206331D02*
X1174321Y-205456D01*
X1173666Y-203998D01*
X1173229Y-201955D01*
X1173666Y-200206D01*
X1174539Y-199039D01*
X1176068Y-198164D01*
X1181963D01*
Y-215664D01*
X1174758D01*
X1173229Y-214498D01*
X1172356Y-212747D01*
X1171919Y-210706D01*
X1172356Y-208664D01*
X1173666Y-206914D01*
X1175195Y-206331D01*
X1181963D01*
G01X1165118Y-215664D02*
Y-198164D01*
X1159441Y-212747D01*
X1153764Y-198164D01*
Y-215664D01*
G01X1147400D02*
X1141941Y-198164D01*
X1136482Y-215664D01*
G01X1138448Y-209539D02*
X1145435D01*
G01X1129026Y-213331D02*
X1127279Y-214789D01*
X1125314Y-215664D01*
X1123568D01*
X1121821Y-214789D01*
X1120511Y-213331D01*
X1119856Y-211289D01*
X1120293Y-209248D01*
X1121384Y-207497D01*
X1123349Y-206331D01*
X1125969Y-205747D01*
X1127498Y-204581D01*
X1128153Y-202539D01*
X1127716Y-200497D01*
X1126624Y-199039D01*
X1125096Y-198164D01*
X1123568D01*
X1122039Y-198747D01*
X1120729Y-200206D01*
G01X1111744Y-215664D02*
Y-198164D01*
G01X1103448D02*
X1111744Y-208956D01*
G01X1102138Y-215664D02*
X1108033Y-203998D01*
G01X1102574Y-153164D02*
Y-170664D01*
X1111308D01*
G01X1128371D02*
Y-158998D01*
G01Y-161039D02*
X1127498Y-159873D01*
X1126187Y-159289D01*
X1124659Y-158998D01*
X1123131Y-159581D01*
X1121821Y-160747D01*
X1120947Y-162497D01*
X1120511Y-164831D01*
X1120947Y-167164D01*
X1121821Y-168914D01*
X1123131Y-170081D01*
X1124659Y-170664D01*
X1126187Y-170372D01*
X1127498Y-169498D01*
X1128371Y-168331D01*
G01X1137356Y-175914D02*
X1138666Y-176497D01*
X1140413Y-175914D01*
X1141504Y-174748D01*
X1142378Y-173289D01*
X1143687Y-168623D01*
X1146526Y-158998D01*
G01X1139539D02*
X1143687Y-168623D01*
G01X1156166Y-162789D02*
X1163153D01*
X1162498Y-160747D01*
X1161406Y-159581D01*
X1159878Y-158998D01*
X1158349Y-159289D01*
X1157039Y-160164D01*
X1156166Y-162206D01*
X1155729Y-163956D01*
Y-165706D01*
X1156166Y-167456D01*
X1157258Y-169206D01*
X1158568Y-170372D01*
X1160096Y-170664D01*
X1161624Y-170081D01*
X1163153Y-168331D01*
G01X1173884Y-170664D02*
Y-158998D01*
G01Y-161331D02*
X1174976Y-160164D01*
X1176068Y-159289D01*
X1177596Y-158998D01*
X1178687Y-159289D01*
X1179998Y-160164D01*
G01X1244688Y-170664D02*
Y-153164D01*
X1249054D01*
X1250801Y-154039D01*
X1252111Y-155206D01*
X1253203Y-156955D01*
X1254076Y-158998D01*
X1254294Y-161914D01*
X1254076Y-164831D01*
X1253203Y-166873D01*
X1252111Y-168623D01*
X1250801Y-169789D01*
X1249054Y-170664D01*
X1244688D01*
G01X1263716Y-162789D02*
X1270703D01*
X1270048Y-160747D01*
X1268956Y-159581D01*
X1267428Y-158998D01*
X1265899Y-159289D01*
X1264589Y-160164D01*
X1263716Y-162206D01*
X1263279Y-163956D01*
Y-165706D01*
X1263716Y-167456D01*
X1264808Y-169206D01*
X1266118Y-170372D01*
X1267646Y-170664D01*
X1269174Y-170081D01*
X1270703Y-168331D01*
G01X1281216Y-168623D02*
X1282308Y-169789D01*
X1283836Y-170664D01*
X1285146D01*
X1286456Y-170081D01*
X1287329Y-169206D01*
X1287766Y-168040D01*
X1287548Y-166289D01*
X1286674Y-165414D01*
X1282744Y-163664D01*
X1281871Y-161622D01*
X1282308Y-160164D01*
X1283181Y-159289D01*
X1284491Y-158998D01*
X1285801Y-159289D01*
X1287111Y-160164D01*
G01X1301991Y-158998D02*
Y-170664D01*
G01Y-154331D02*
X1301554Y-154039D01*
Y-153456D01*
X1301991Y-153164D01*
X1302428Y-153456D01*
Y-154039D01*
X1301991Y-154331D01*
G01X1316434Y-175039D02*
X1317963Y-176206D01*
X1319709Y-176497D01*
X1321237Y-176206D01*
X1322548Y-174748D01*
X1323421Y-172706D01*
Y-158998D01*
G01Y-161331D02*
X1322548Y-160164D01*
X1321237Y-159289D01*
X1319709Y-158998D01*
X1317963Y-159581D01*
X1316871Y-160747D01*
X1315997Y-162789D01*
X1315561Y-164831D01*
X1315779Y-166581D01*
X1316653Y-168623D01*
X1317963Y-170081D01*
X1319709Y-170664D01*
X1321019Y-170372D01*
X1322548Y-169206D01*
X1323421Y-168040D01*
G01X1333279Y-170664D02*
Y-158998D01*
G01Y-161914D02*
X1334153Y-160456D01*
X1335463Y-159289D01*
X1337209Y-158998D01*
X1338737Y-159289D01*
X1340048Y-160456D01*
X1340703Y-162497D01*
Y-170664D01*
G01X1351216Y-162789D02*
X1358203D01*
X1357548Y-160747D01*
X1356456Y-159581D01*
X1354928Y-158998D01*
X1353399Y-159289D01*
X1352089Y-160164D01*
X1351216Y-162206D01*
X1350779Y-163956D01*
Y-165706D01*
X1351216Y-167456D01*
X1352308Y-169206D01*
X1353618Y-170372D01*
X1355146Y-170664D01*
X1356674Y-170081D01*
X1358203Y-168331D01*
G01X1368934Y-170664D02*
Y-158998D01*
G01Y-161331D02*
X1370026Y-160164D01*
X1371118Y-159289D01*
X1372646Y-158998D01*
X1373737Y-159289D01*
X1375048Y-160164D01*
G01X1266991Y-215664D02*
X1265244Y-215372D01*
X1263716Y-214206D01*
X1262406Y-212456D01*
X1261532Y-210414D01*
X1261096Y-208081D01*
Y-205747D01*
X1261532Y-203414D01*
X1262406Y-201372D01*
X1263716Y-199623D01*
X1265244Y-198456D01*
X1266991Y-198164D01*
X1268737Y-198456D01*
X1270266Y-199623D01*
X1271576Y-201372D01*
X1272450Y-203414D01*
X1272886Y-205747D01*
Y-208081D01*
X1272450Y-210414D01*
X1271576Y-212456D01*
X1270266Y-214206D01*
X1268737Y-215372D01*
X1266991Y-215664D01*
G01X1268737Y-210997D02*
X1271358Y-215664D01*
G01X1279688Y-198164D02*
Y-210706D01*
X1280561Y-213331D01*
X1282308Y-215081D01*
X1284491Y-215664D01*
X1286674Y-215081D01*
X1288421Y-213331D01*
X1289294Y-210706D01*
Y-198164D01*
G01X1299371D02*
X1304611D01*
G01X1301991D02*
Y-215664D01*
G01X1299371D02*
X1304611D01*
G01X1314469D02*
Y-198164D01*
X1324513Y-215664D01*
Y-198164D01*
G01X1341794Y-199623D02*
X1340484Y-198747D01*
X1338956Y-198164D01*
X1337209D01*
X1335244Y-199039D01*
X1333716Y-200497D01*
X1332624Y-202248D01*
X1331751Y-205164D01*
X1331532Y-207789D01*
X1331969Y-210414D01*
X1332624Y-212164D01*
X1333934Y-213914D01*
X1335463Y-215081D01*
X1336991Y-215664D01*
X1338519D01*
X1340048Y-215081D01*
X1341358Y-214206D01*
X1342450Y-213040D01*
G01X1354491Y-215664D02*
Y-207789D01*
X1350124Y-198164D01*
G01X1358858D02*
X1354491Y-207789D01*
G01X1415691Y-198164D02*
X1413944Y-198747D01*
X1412634Y-200206D01*
X1411761Y-201955D01*
X1411106Y-204289D01*
X1410888Y-206914D01*
X1411106Y-209539D01*
X1411761Y-211873D01*
X1412634Y-213623D01*
X1413944Y-215081D01*
X1415691Y-215664D01*
X1417437Y-215081D01*
X1418748Y-213623D01*
X1419621Y-211873D01*
X1420276Y-209539D01*
X1420494Y-206914D01*
X1420276Y-204289D01*
X1419621Y-201955D01*
X1418748Y-200206D01*
X1417437Y-198747D01*
X1415691Y-198164D01*
G01X1429043Y-208373D02*
X1430571Y-206331D01*
X1431881Y-205164D01*
X1433628Y-204581D01*
X1435156Y-205164D01*
X1436248Y-206331D01*
X1437121Y-208081D01*
X1437339Y-210122D01*
X1437121Y-211873D01*
X1436248Y-213623D01*
X1434937Y-215081D01*
X1433409Y-215664D01*
X1431663Y-215081D01*
X1430134Y-213331D01*
X1429261Y-210706D01*
X1429043Y-207789D01*
X1429479Y-203998D01*
X1430134Y-201955D01*
X1431226Y-199914D01*
X1432754Y-198456D01*
X1434283Y-198164D01*
X1435811Y-198747D01*
X1436903Y-200206D01*
G01X1446761Y-216247D02*
X1454621Y-198164D01*
G01X1468191D02*
X1466444Y-198747D01*
X1465134Y-200206D01*
X1464261Y-201955D01*
X1463606Y-204289D01*
X1463388Y-206914D01*
X1463606Y-209539D01*
X1464261Y-211873D01*
X1465134Y-213623D01*
X1466444Y-215081D01*
X1468191Y-215664D01*
X1469937Y-215081D01*
X1471248Y-213623D01*
X1472121Y-211873D01*
X1472776Y-209539D01*
X1472994Y-206914D01*
X1472776Y-204289D01*
X1472121Y-201955D01*
X1471248Y-200206D01*
X1469937Y-198747D01*
X1468191Y-198164D01*
G01X1481979Y-213623D02*
X1483508Y-215081D01*
X1485254Y-215664D01*
X1487001Y-215081D01*
X1488529Y-213331D01*
X1489621Y-210706D01*
X1490058Y-208081D01*
Y-204873D01*
X1489621Y-202248D01*
X1488529Y-199914D01*
X1487219Y-198747D01*
X1485691Y-198164D01*
X1483944Y-198747D01*
X1482634Y-199914D01*
X1481761Y-201664D01*
X1481324Y-203998D01*
X1481761Y-206039D01*
X1482853Y-208081D01*
X1484163Y-209248D01*
X1485691Y-209539D01*
X1487437Y-208956D01*
X1488748Y-207497D01*
X1490058Y-204873D01*
G01X1499261Y-216247D02*
X1507121Y-198164D01*
G01X1516543Y-201081D02*
X1517853Y-199331D01*
X1519381Y-198456D01*
X1521128Y-198164D01*
X1523311Y-198747D01*
X1524839Y-200206D01*
X1525276Y-201955D01*
X1525058Y-203706D01*
X1524184Y-205164D01*
X1519818Y-208081D01*
X1517853Y-210122D01*
X1516543Y-213040D01*
X1516106Y-215664D01*
X1525276D01*
G01X1538191Y-198164D02*
X1536444Y-198747D01*
X1535134Y-200206D01*
X1534261Y-201955D01*
X1533606Y-204289D01*
X1533388Y-206914D01*
X1533606Y-209539D01*
X1534261Y-211873D01*
X1535134Y-213623D01*
X1536444Y-215081D01*
X1538191Y-215664D01*
X1539937Y-215081D01*
X1541248Y-213623D01*
X1542121Y-211873D01*
X1542776Y-209539D01*
X1542994Y-206914D01*
X1542776Y-204289D01*
X1542121Y-201955D01*
X1541248Y-200206D01*
X1539937Y-198747D01*
X1538191Y-198164D01*
G01X1555691Y-215664D02*
Y-198164D01*
X1553071Y-201664D01*
G01Y-215664D02*
X1558311D01*
G01X1572754D02*
X1573191Y-211873D01*
X1573846Y-208664D01*
X1574719Y-205747D01*
X1575811Y-202539D01*
X1577558Y-198164D01*
X1568824D01*
G01X1463388Y-170664D02*
Y-153164D01*
X1467754D01*
X1469501Y-154039D01*
X1470811Y-155206D01*
X1471903Y-156955D01*
X1472776Y-158998D01*
X1472994Y-161914D01*
X1472776Y-164831D01*
X1471903Y-166873D01*
X1470811Y-168623D01*
X1469501Y-169789D01*
X1467754Y-170664D01*
X1463388D01*
G01X1489621D02*
Y-158998D01*
G01Y-161039D02*
X1488748Y-159873D01*
X1487437Y-159289D01*
X1485909Y-158998D01*
X1484381Y-159581D01*
X1483071Y-160747D01*
X1482197Y-162497D01*
X1481761Y-164831D01*
X1482197Y-167164D01*
X1483071Y-168914D01*
X1484381Y-170081D01*
X1485909Y-170664D01*
X1487437Y-170372D01*
X1488748Y-169498D01*
X1489621Y-168331D01*
G01X1503191Y-153164D02*
Y-170664D01*
G01X1500134Y-158998D02*
X1506248D01*
G01X1517416Y-162789D02*
X1524403D01*
X1523748Y-160747D01*
X1522656Y-159581D01*
X1521128Y-158998D01*
X1519599Y-159289D01*
X1518289Y-160164D01*
X1517416Y-162206D01*
X1516979Y-163956D01*
Y-165706D01*
X1517416Y-167456D01*
X1518508Y-169206D01*
X1519818Y-170372D01*
X1521346Y-170664D01*
X1522874Y-170081D01*
X1524403Y-168331D01*
G54D49*
X246535Y1320472D03*
X531535D03*
G54D67*
X1021216Y1137521D03*
G54D58*
X669470Y1464200D03*
X1022935Y1126478D03*
X1016645Y1103242D03*
G54D68*
X1021216Y1143121D03*
G54D59*
X862205Y277953D03*
X848032D03*
X833859D03*
X862205Y272441D03*
X848032D03*
X833859D03*
X862205Y263779D03*
X848032D03*
X833859D03*
X862205Y258268D03*
X848032D03*
X833859D03*
X862205Y282283D03*
X848032D03*
X833859D03*
X862205Y268110D03*
X848032D03*
X833859D03*
X862205Y253937D03*
X848032D03*
X833859D03*
X855118Y282677D03*
X840945D03*
X826772D03*
X855118Y277165D03*
X840945D03*
X826772D03*
X855118Y272835D03*
X840945D03*
X826772D03*
X855118Y268504D03*
X840945D03*
X826772D03*
X855118Y262992D03*
X840945D03*
X826772D03*
X862205Y306299D03*
X848032D03*
X833859D03*
X862205Y300787D03*
X848032D03*
X833859D03*
X862205Y292126D03*
X848032D03*
X833859D03*
X862205Y286614D03*
X848032D03*
X833859D03*
X862205Y310630D03*
X848032D03*
X833859D03*
X862205Y296457D03*
X848032D03*
X833859D03*
X855118Y311023D03*
X840945D03*
X826772D03*
X855118Y305512D03*
X840945D03*
X826772D03*
X855118Y296850D03*
X840945D03*
X826772D03*
X855118Y291338D03*
X840945D03*
X826772D03*
X855118Y315354D03*
X840945D03*
X826772D03*
X855118Y301181D03*
X840945D03*
X826772D03*
X855118Y287008D03*
X840945D03*
X826772D03*
X904725Y272835D03*
Y277165D03*
Y282677D03*
X911811Y272441D03*
Y277953D03*
Y282283D03*
X904725Y262992D03*
Y268504D03*
X911811Y253937D03*
Y258268D03*
Y263779D03*
Y268110D03*
X897638Y282283D03*
Y272441D03*
Y277953D03*
Y253937D03*
Y268110D03*
Y258268D03*
Y263779D03*
X890552Y272835D03*
Y277165D03*
Y282677D03*
Y262992D03*
Y268504D03*
X876378Y277953D03*
Y272441D03*
Y263779D03*
Y258268D03*
Y282283D03*
Y268110D03*
Y253937D03*
X869292Y282677D03*
Y277165D03*
Y272835D03*
Y268504D03*
Y262992D03*
X904725Y305512D03*
Y311023D03*
Y315354D03*
X911811Y306299D03*
Y310630D03*
X904725Y301181D03*
X911811Y300787D03*
X904725Y287008D03*
Y291338D03*
Y296850D03*
X911811Y286614D03*
Y292126D03*
Y296457D03*
X897638Y310630D03*
Y306299D03*
Y296457D03*
Y286614D03*
Y292126D03*
Y300787D03*
X890552Y315354D03*
Y305512D03*
Y311023D03*
Y287008D03*
Y301181D03*
Y291338D03*
Y296850D03*
X876378Y306299D03*
Y300787D03*
Y292126D03*
Y286614D03*
Y310630D03*
Y296457D03*
X869292Y311023D03*
Y305512D03*
Y296850D03*
Y291338D03*
Y315354D03*
Y301181D03*
Y287008D03*
X1091089Y520057D03*
X1095420D03*
X1100932D03*
X1105262D03*
X1109593D03*
X1115105D03*
X1119435D03*
X1123766D03*
X1129278D03*
X1133609D03*
X1095026Y527143D03*
X1099357D03*
X1104869D03*
X1109199D03*
X1113530D03*
X1119042D03*
X1123372D03*
X1127703D03*
X1133215D03*
X1091089Y534230D03*
X1095420D03*
X1100932D03*
X1105262D03*
X1109593D03*
X1115105D03*
X1119435D03*
X1123766D03*
X1129278D03*
X1133609D03*
X1095026Y541317D03*
X1099357D03*
X1104869D03*
X1109199D03*
X1113530D03*
X1119042D03*
X1123372D03*
X1127703D03*
X1133215D03*
X1091089Y548403D03*
X1095420D03*
X1100932D03*
X1105262D03*
X1109593D03*
X1115105D03*
X1119435D03*
X1123766D03*
X1129278D03*
X1133609D03*
X1095026Y555490D03*
X1099357D03*
X1104869D03*
X1109199D03*
X1113530D03*
X1119042D03*
X1123372D03*
X1127703D03*
X1133215D03*
X1091089Y562576D03*
X1095420D03*
X1100932D03*
X1105262D03*
X1109593D03*
X1115105D03*
X1119435D03*
X1123766D03*
X1129278D03*
X1133609D03*
X1095026Y569663D03*
X1099357D03*
X1104869D03*
X1109199D03*
X1113530D03*
X1119042D03*
X1123372D03*
X1127703D03*
X1133215D03*
X1091089Y691711D03*
Y705884D03*
Y720057D03*
Y734230D03*
Y748403D03*
Y762577D03*
X1095420Y691711D03*
Y705884D03*
Y720057D03*
Y734230D03*
Y748403D03*
Y762577D03*
X1100932Y691711D03*
Y705884D03*
Y720057D03*
Y734230D03*
Y748403D03*
Y762577D03*
X1105262Y691711D03*
Y705884D03*
Y720057D03*
Y734230D03*
Y748403D03*
Y762577D03*
X1109593Y691711D03*
Y705884D03*
Y720057D03*
Y734230D03*
Y748403D03*
Y762577D03*
X1115105Y691711D03*
Y705884D03*
Y720057D03*
Y734230D03*
Y748403D03*
Y762577D03*
X1119435Y691711D03*
Y705884D03*
Y720057D03*
Y734230D03*
Y748403D03*
Y762577D03*
X1123766Y691711D03*
Y705884D03*
Y720057D03*
Y734230D03*
Y748403D03*
Y762577D03*
X1129278Y691711D03*
Y705884D03*
Y720057D03*
Y734230D03*
Y748403D03*
Y762577D03*
X1133609Y691711D03*
Y705884D03*
Y720057D03*
Y734230D03*
Y748403D03*
Y762577D03*
X1095026Y698797D03*
Y712970D03*
Y727144D03*
Y741317D03*
Y755490D03*
X1099357Y698797D03*
Y712970D03*
Y727144D03*
Y741317D03*
Y755490D03*
X1104869Y698797D03*
Y712970D03*
Y727144D03*
Y741317D03*
Y755490D03*
X1109199Y698797D03*
Y712970D03*
Y727144D03*
Y741317D03*
Y755490D03*
X1113530Y698797D03*
Y712970D03*
Y727144D03*
Y741317D03*
Y755490D03*
X1119042Y698797D03*
Y712970D03*
Y727144D03*
Y741317D03*
Y755490D03*
X1123372Y698797D03*
Y712970D03*
Y727144D03*
Y741317D03*
Y755490D03*
X1127703Y698797D03*
Y712970D03*
Y727144D03*
Y741317D03*
Y755490D03*
X1133215Y698797D03*
Y712970D03*
Y727144D03*
Y741317D03*
Y755490D03*
X1091089Y776750D03*
Y790923D03*
Y805096D03*
Y819270D03*
Y833443D03*
Y847616D03*
X1095420Y776750D03*
Y790923D03*
Y805096D03*
Y819270D03*
Y833443D03*
Y847616D03*
X1100932Y776750D03*
Y790923D03*
Y805096D03*
Y819270D03*
Y833443D03*
Y847616D03*
X1105262Y776750D03*
Y790923D03*
Y805096D03*
Y819270D03*
Y833443D03*
Y847616D03*
X1109593Y776750D03*
Y790923D03*
Y805096D03*
Y819270D03*
Y833443D03*
Y847616D03*
X1115105Y776750D03*
Y790923D03*
Y805096D03*
Y819270D03*
Y833443D03*
Y847616D03*
X1119435Y776750D03*
Y790923D03*
Y805096D03*
Y819270D03*
Y833443D03*
Y847616D03*
X1123766Y776750D03*
Y790923D03*
Y805096D03*
Y819270D03*
Y833443D03*
Y847616D03*
X1129278Y776750D03*
Y790923D03*
Y805096D03*
Y819270D03*
Y833443D03*
Y847616D03*
X1133609Y776750D03*
Y790923D03*
Y805096D03*
Y819270D03*
Y833443D03*
Y847616D03*
X1095026Y769663D03*
Y783836D03*
Y798010D03*
Y812183D03*
Y826356D03*
Y840529D03*
Y854703D03*
X1099357Y769663D03*
Y783836D03*
Y798010D03*
Y812183D03*
Y826356D03*
Y840529D03*
Y854703D03*
X1104869Y769663D03*
Y783836D03*
Y798010D03*
Y812183D03*
Y826356D03*
Y840529D03*
Y854703D03*
X1109199Y769663D03*
Y783836D03*
Y798010D03*
Y812183D03*
Y826356D03*
Y840529D03*
Y854703D03*
X1113530Y769663D03*
Y783836D03*
Y798010D03*
Y812183D03*
Y826356D03*
Y840529D03*
Y854703D03*
X1119042Y769663D03*
Y783836D03*
Y798010D03*
Y812183D03*
Y826356D03*
Y840529D03*
Y854703D03*
X1123372Y769663D03*
Y783836D03*
Y798010D03*
Y812183D03*
Y826356D03*
Y840529D03*
Y854703D03*
X1127703Y769663D03*
Y783836D03*
Y798010D03*
Y812183D03*
Y826356D03*
Y840529D03*
Y854703D03*
X1133215Y769663D03*
Y783836D03*
Y798010D03*
Y812183D03*
Y826356D03*
Y840529D03*
Y854703D03*
X1091089Y861789D03*
Y875962D03*
Y890136D03*
Y904309D03*
Y918482D03*
Y932655D03*
X1095420Y861789D03*
Y875962D03*
Y890136D03*
Y904309D03*
Y918482D03*
Y932655D03*
X1100932Y861789D03*
Y875962D03*
Y890136D03*
Y904309D03*
Y918482D03*
Y932655D03*
X1105262Y861789D03*
Y875962D03*
Y890136D03*
Y904309D03*
Y918482D03*
Y932655D03*
X1109593Y861789D03*
Y875962D03*
Y890136D03*
Y904309D03*
Y918482D03*
Y932655D03*
X1115105Y861789D03*
Y875962D03*
Y890136D03*
Y904309D03*
Y918482D03*
Y932655D03*
X1119435Y861789D03*
Y875962D03*
Y890136D03*
Y904309D03*
Y918482D03*
Y932655D03*
X1123766Y861789D03*
Y875962D03*
Y890136D03*
Y904309D03*
Y918482D03*
Y932655D03*
X1129278Y861789D03*
Y875962D03*
Y890136D03*
Y904309D03*
Y918482D03*
Y932655D03*
X1133609Y861789D03*
Y875962D03*
Y890136D03*
Y904309D03*
Y918482D03*
Y932655D03*
X1095026Y868876D03*
Y883049D03*
Y897222D03*
Y911396D03*
Y925569D03*
Y939742D03*
X1099357Y868876D03*
Y883049D03*
Y897222D03*
Y911396D03*
Y925569D03*
Y939742D03*
X1104869Y868876D03*
Y883049D03*
Y897222D03*
Y911396D03*
Y925569D03*
Y939742D03*
X1109199Y868876D03*
Y883049D03*
Y897222D03*
Y911396D03*
Y925569D03*
Y939742D03*
X1113530Y868876D03*
Y883049D03*
Y897222D03*
Y911396D03*
Y925569D03*
Y939742D03*
X1119042Y868876D03*
Y883049D03*
Y897222D03*
Y911396D03*
Y925569D03*
Y939742D03*
X1123372Y868876D03*
Y883049D03*
Y897222D03*
Y911396D03*
Y925569D03*
Y939742D03*
X1127703Y868876D03*
Y883049D03*
Y897222D03*
Y911396D03*
Y925569D03*
Y939742D03*
X1133215Y868876D03*
Y883049D03*
Y897222D03*
Y911396D03*
Y925569D03*
Y939742D03*
G54D69*
X1002000Y1144000D03*
X1013000D03*
M02*
